G04*
G04 #@! TF.GenerationSoftware,Altium Limited,Altium Designer,23.6.0 (18)*
G04*
G04 Layer_Color=32896*
%FSLAX44Y44*%
%MOMM*%
G71*
G04*
G04 #@! TF.SameCoordinates,59133E90-4310-4D8A-9E2C-91A8D2F69FBB*
G04*
G04*
G04 #@! TF.FilePolarity,Positive*
G04*
G01*
G75*
%ADD64C,0.1000*%
G36*
X25444Y350267D02*
X25582D01*
Y349718D01*
X25719D01*
Y349444D01*
X25856D01*
Y349169D01*
X25994D01*
Y348894D01*
X26131D01*
Y348757D01*
X26268D01*
Y348482D01*
X26406D01*
Y348345D01*
X26543D01*
Y348208D01*
X26680D01*
Y348070D01*
X26955D01*
Y347933D01*
X27092D01*
Y347796D01*
X27367D01*
Y347659D01*
X27641D01*
Y347521D01*
X27916D01*
Y347384D01*
X28603D01*
Y347247D01*
X177180D01*
Y342166D01*
X27229D01*
Y342303D01*
X26543D01*
Y342440D01*
X25994D01*
Y342578D01*
X25719D01*
Y342715D01*
X25307D01*
Y342852D01*
X25032D01*
Y342990D01*
X24758D01*
Y343127D01*
X24483D01*
Y343264D01*
X24209D01*
Y343402D01*
X24071D01*
Y343539D01*
X23797D01*
Y343676D01*
X23659D01*
Y343814D01*
X23522D01*
Y343951D01*
X23247D01*
Y344088D01*
X23110D01*
Y344226D01*
X22973D01*
Y344363D01*
X22835D01*
Y344500D01*
X22698D01*
Y344637D01*
X22561D01*
Y344775D01*
X22423D01*
Y344912D01*
X22286D01*
Y345049D01*
X22149D01*
Y345324D01*
X22011D01*
Y345461D01*
X21874D01*
Y345599D01*
X21737D01*
Y345873D01*
X21600D01*
Y346011D01*
X21462D01*
Y346285D01*
X21325D01*
Y346560D01*
X21188D01*
Y346835D01*
X21050D01*
Y347109D01*
X20913D01*
Y347521D01*
X20776D01*
Y347796D01*
X20638D01*
Y348345D01*
X20501D01*
Y348894D01*
X20364D01*
Y350267D01*
X20226D01*
Y367707D01*
X25444D01*
Y350267D01*
D02*
G37*
G36*
X139143Y336398D02*
X139830D01*
Y336261D01*
X140242D01*
Y336124D01*
X140517D01*
Y335987D01*
X140791D01*
Y335849D01*
X141066D01*
Y335712D01*
X141340D01*
Y335574D01*
X141478D01*
Y335437D01*
X141752D01*
Y335300D01*
X141890D01*
Y335163D01*
X142027D01*
Y335025D01*
X142164D01*
Y334888D01*
X142302D01*
Y334751D01*
X142439D01*
Y334476D01*
X142576D01*
Y334339D01*
X142714D01*
Y334201D01*
X142851D01*
Y333927D01*
X142988D01*
Y333652D01*
X143125D01*
Y333377D01*
X143263D01*
Y332966D01*
X143400D01*
Y332553D01*
X143538D01*
Y330219D01*
X143400D01*
Y329807D01*
X143263D01*
Y329395D01*
X143125D01*
Y329121D01*
X142988D01*
Y328846D01*
X142851D01*
Y328571D01*
X142714D01*
Y328434D01*
X142576D01*
Y328159D01*
X142439D01*
Y328022D01*
X142302D01*
Y327885D01*
X142164D01*
Y327747D01*
X142027D01*
Y327610D01*
X141890D01*
Y327473D01*
X141752D01*
Y327336D01*
X141615D01*
Y327198D01*
X141340D01*
Y327061D01*
X141203D01*
Y326923D01*
X140928D01*
Y326786D01*
X140654D01*
Y326649D01*
X140379D01*
Y326512D01*
X139967D01*
Y326374D01*
X139281D01*
Y326237D01*
X137633D01*
Y326374D01*
X136946D01*
Y326512D01*
X136534D01*
Y326649D01*
X136260D01*
Y326786D01*
X135985D01*
Y326923D01*
X135710D01*
Y327061D01*
X135573D01*
Y327198D01*
X135298D01*
Y327336D01*
X135161D01*
Y327473D01*
X135024D01*
Y327610D01*
X134887D01*
Y327747D01*
X134749D01*
Y327885D01*
X134612D01*
Y328022D01*
X134474D01*
Y328159D01*
X134337D01*
Y328434D01*
X134200D01*
Y328571D01*
X134063D01*
Y328846D01*
X133925D01*
Y329121D01*
X133788D01*
Y329395D01*
X133651D01*
Y329670D01*
X133513D01*
Y330219D01*
X133376D01*
Y332553D01*
X133513D01*
Y332966D01*
X133651D01*
Y333377D01*
X133788D01*
Y333652D01*
X133925D01*
Y333927D01*
X134063D01*
Y334201D01*
X134200D01*
Y334339D01*
X134337D01*
Y334613D01*
X134474D01*
Y334751D01*
X134612D01*
Y334888D01*
X134749D01*
Y335025D01*
X134887D01*
Y335163D01*
X135024D01*
Y335300D01*
X135161D01*
Y335437D01*
X135436D01*
Y335574D01*
X135573D01*
Y335712D01*
X135848D01*
Y335849D01*
X136122D01*
Y335987D01*
X136397D01*
Y336124D01*
X136672D01*
Y336261D01*
X137084D01*
Y336398D01*
X137770D01*
Y336536D01*
X139143D01*
Y336398D01*
D02*
G37*
G36*
X120605D02*
X121292D01*
Y336261D01*
X121704D01*
Y336124D01*
X121979D01*
Y335987D01*
X122253D01*
Y335849D01*
X122528D01*
Y335712D01*
X122802D01*
Y335574D01*
X122940D01*
Y335437D01*
X123077D01*
Y335300D01*
X123352D01*
Y335163D01*
X123489D01*
Y335025D01*
X123626D01*
Y334888D01*
X123764D01*
Y334613D01*
X123901D01*
Y334476D01*
X124038D01*
Y334339D01*
X124176D01*
Y334064D01*
X124313D01*
Y333789D01*
X124450D01*
Y333652D01*
X124588D01*
Y333240D01*
X124725D01*
Y332828D01*
X124862D01*
Y332416D01*
X125000D01*
Y330356D01*
X124862D01*
Y329807D01*
X124725D01*
Y329533D01*
X124588D01*
Y329121D01*
X124450D01*
Y328846D01*
X124313D01*
Y328709D01*
X124176D01*
Y328434D01*
X124038D01*
Y328297D01*
X123901D01*
Y328022D01*
X123764D01*
Y327885D01*
X123626D01*
Y327747D01*
X123489D01*
Y327610D01*
X123352D01*
Y327473D01*
X123215D01*
Y327336D01*
X122940D01*
Y327198D01*
X122802D01*
Y327061D01*
X122528D01*
Y326923D01*
X122391D01*
Y326786D01*
X122116D01*
Y326649D01*
X121704D01*
Y326512D01*
X121292D01*
Y326374D01*
X120743D01*
Y326237D01*
X118958D01*
Y326374D01*
X118408D01*
Y326512D01*
X117996D01*
Y326649D01*
X117722D01*
Y326786D01*
X117447D01*
Y326923D01*
X117172D01*
Y327061D01*
X117035D01*
Y327198D01*
X116761D01*
Y327336D01*
X116623D01*
Y327473D01*
X116486D01*
Y327610D01*
X116349D01*
Y327747D01*
X116211D01*
Y327885D01*
X116074D01*
Y328022D01*
X115937D01*
Y328159D01*
X115799D01*
Y328297D01*
X115662D01*
Y328571D01*
X115525D01*
Y328709D01*
X115387D01*
Y328983D01*
X115250D01*
Y329258D01*
X115113D01*
Y329670D01*
X114975D01*
Y330082D01*
X114838D01*
Y330768D01*
X114701D01*
Y332004D01*
X114838D01*
Y332691D01*
X114975D01*
Y333103D01*
X115113D01*
Y333515D01*
X115250D01*
Y333789D01*
X115387D01*
Y333927D01*
X115525D01*
Y334201D01*
X115662D01*
Y334476D01*
X115799D01*
Y334613D01*
X115937D01*
Y334751D01*
X116074D01*
Y334888D01*
X116211D01*
Y335025D01*
X116349D01*
Y335163D01*
X116486D01*
Y335300D01*
X116623D01*
Y335437D01*
X116761D01*
Y335574D01*
X117035D01*
Y335712D01*
X117172D01*
Y335849D01*
X117447D01*
Y335987D01*
X117722D01*
Y336124D01*
X118134D01*
Y336261D01*
X118546D01*
Y336398D01*
X119232D01*
Y336536D01*
X120605D01*
Y336398D01*
D02*
G37*
G36*
X102068D02*
X102617D01*
Y336261D01*
X103029D01*
Y336124D01*
X103441D01*
Y335987D01*
X103715D01*
Y335849D01*
X103990D01*
Y335712D01*
X104127D01*
Y335574D01*
X104402D01*
Y335437D01*
X104539D01*
Y335300D01*
X104677D01*
Y335163D01*
X104814D01*
Y335025D01*
X104951D01*
Y334888D01*
X105089D01*
Y334751D01*
X105226D01*
Y334613D01*
X105363D01*
Y334476D01*
X105500D01*
Y334201D01*
X105638D01*
Y334064D01*
X105775D01*
Y333789D01*
X105913D01*
Y333515D01*
X106050D01*
Y333240D01*
X106187D01*
Y332828D01*
X106324D01*
Y332142D01*
X106462D01*
Y330631D01*
X106324D01*
Y329944D01*
X106187D01*
Y329533D01*
X106050D01*
Y329258D01*
X105913D01*
Y328983D01*
X105775D01*
Y328709D01*
X105638D01*
Y328434D01*
X105500D01*
Y328297D01*
X105363D01*
Y328159D01*
X105226D01*
Y328022D01*
X105089D01*
Y327747D01*
X104951D01*
Y327610D01*
X104814D01*
Y327473D01*
X104539D01*
Y327336D01*
X104402D01*
Y327198D01*
X104265D01*
Y327061D01*
X103990D01*
Y326923D01*
X103715D01*
Y326786D01*
X103441D01*
Y326649D01*
X103166D01*
Y326512D01*
X102754D01*
Y326374D01*
X102205D01*
Y326237D01*
X100420D01*
Y326374D01*
X99871D01*
Y326512D01*
X99459D01*
Y326649D01*
X99184D01*
Y326786D01*
X98909D01*
Y326923D01*
X98635D01*
Y327061D01*
X98360D01*
Y327198D01*
X98223D01*
Y327336D01*
X98085D01*
Y327473D01*
X97811D01*
Y327610D01*
X97673D01*
Y327747D01*
X97536D01*
Y327885D01*
X97399D01*
Y328159D01*
X97261D01*
Y328297D01*
X97124D01*
Y328434D01*
X96987D01*
Y328709D01*
X96849D01*
Y328983D01*
X96712D01*
Y329258D01*
X96575D01*
Y329533D01*
X96438D01*
Y329944D01*
X96300D01*
Y330494D01*
X96163D01*
Y332142D01*
X96300D01*
Y332828D01*
X96438D01*
Y333240D01*
X96575D01*
Y333515D01*
X96712D01*
Y333789D01*
X96849D01*
Y334064D01*
X96987D01*
Y334201D01*
X97124D01*
Y334476D01*
X97261D01*
Y334613D01*
X97399D01*
Y334751D01*
X97536D01*
Y334888D01*
X97673D01*
Y335025D01*
X97811D01*
Y335163D01*
X97948D01*
Y335300D01*
X98085D01*
Y335437D01*
X98223D01*
Y335574D01*
X98497D01*
Y335712D01*
X98635D01*
Y335849D01*
X98909D01*
Y335987D01*
X99184D01*
Y336124D01*
X99459D01*
Y336261D01*
X100008D01*
Y336398D01*
X100557D01*
Y336536D01*
X102068D01*
Y336398D01*
D02*
G37*
G36*
X83392D02*
X84079D01*
Y336261D01*
X84491D01*
Y336124D01*
X84903D01*
Y335987D01*
X85177D01*
Y335849D01*
X85315D01*
Y335712D01*
X85590D01*
Y335574D01*
X85864D01*
Y335437D01*
X86001D01*
Y335300D01*
X86139D01*
Y335163D01*
X86276D01*
Y335025D01*
X86413D01*
Y334888D01*
X86551D01*
Y334751D01*
X86688D01*
Y334613D01*
X86825D01*
Y334339D01*
X86963D01*
Y334201D01*
X87100D01*
Y333927D01*
X87237D01*
Y333789D01*
X87375D01*
Y333377D01*
X87512D01*
Y333103D01*
X87649D01*
Y332691D01*
X87787D01*
Y331867D01*
X87924D01*
Y330906D01*
X87787D01*
Y330082D01*
X87649D01*
Y329670D01*
X87512D01*
Y329258D01*
X87375D01*
Y328983D01*
X87237D01*
Y328709D01*
X87100D01*
Y328571D01*
X86963D01*
Y328297D01*
X86825D01*
Y328159D01*
X86688D01*
Y328022D01*
X86551D01*
Y327885D01*
X86413D01*
Y327747D01*
X86276D01*
Y327610D01*
X86139D01*
Y327473D01*
X86001D01*
Y327336D01*
X85864D01*
Y327198D01*
X85590D01*
Y327061D01*
X85452D01*
Y326923D01*
X85177D01*
Y326786D01*
X84903D01*
Y326649D01*
X84628D01*
Y326512D01*
X84216D01*
Y326374D01*
X83667D01*
Y326237D01*
X81882D01*
Y326374D01*
X81333D01*
Y326512D01*
X80921D01*
Y326649D01*
X80509D01*
Y326786D01*
X80234D01*
Y326923D01*
X80097D01*
Y327061D01*
X79822D01*
Y327198D01*
X79685D01*
Y327336D01*
X79410D01*
Y327473D01*
X79273D01*
Y327610D01*
X79136D01*
Y327747D01*
X78998D01*
Y327885D01*
X78861D01*
Y328022D01*
X78724D01*
Y328297D01*
X78586D01*
Y328434D01*
X78449D01*
Y328709D01*
X78312D01*
Y328846D01*
X78174D01*
Y329121D01*
X78037D01*
Y329395D01*
X77900D01*
Y329807D01*
X77762D01*
Y330356D01*
X77625D01*
Y332416D01*
X77762D01*
Y332966D01*
X77900D01*
Y333240D01*
X78037D01*
Y333652D01*
X78174D01*
Y333927D01*
X78312D01*
Y334064D01*
X78449D01*
Y334339D01*
X78586D01*
Y334476D01*
X78724D01*
Y334613D01*
X78861D01*
Y334888D01*
X78998D01*
Y335025D01*
X79136D01*
Y335163D01*
X79273D01*
Y335300D01*
X79548D01*
Y335437D01*
X79685D01*
Y335574D01*
X79822D01*
Y335712D01*
X80097D01*
Y335849D01*
X80371D01*
Y335987D01*
X80646D01*
Y336124D01*
X80921D01*
Y336261D01*
X81333D01*
Y336398D01*
X82019D01*
Y336536D01*
X83392D01*
Y336398D01*
D02*
G37*
G36*
X158368Y316625D02*
X146421D01*
Y316487D01*
X146146D01*
Y316350D01*
X146009D01*
Y316213D01*
X145872D01*
Y316075D01*
X145735D01*
Y315801D01*
X145597D01*
Y294517D01*
X145735D01*
Y294242D01*
X145872D01*
Y293967D01*
X146009D01*
Y293830D01*
X146284D01*
Y293693D01*
X147108D01*
Y293555D01*
X147245D01*
Y293693D01*
X147382D01*
Y293555D01*
X147657D01*
Y293693D01*
X154660D01*
Y293555D01*
X155072D01*
Y293418D01*
X155210D01*
Y293281D01*
X155347D01*
Y293143D01*
X155484D01*
Y293006D01*
X155621D01*
Y292594D01*
X155759D01*
Y284355D01*
X155621D01*
Y283943D01*
X155484D01*
Y283806D01*
X155347D01*
Y283668D01*
X155210D01*
Y283531D01*
X155072D01*
Y283394D01*
X154523D01*
Y283257D01*
X148618D01*
Y283394D01*
X148481D01*
Y283257D01*
X148206D01*
Y283394D01*
X148069D01*
Y283257D01*
X147245D01*
Y283119D01*
X146970D01*
Y282982D01*
X146696D01*
Y282845D01*
X146559D01*
Y282707D01*
X146421D01*
Y282570D01*
X146284D01*
Y282433D01*
X146146D01*
Y282295D01*
X146009D01*
Y282021D01*
X145872D01*
Y281746D01*
X145735D01*
Y281334D01*
X145597D01*
Y280236D01*
X145735D01*
Y279824D01*
X145872D01*
Y279549D01*
X146009D01*
Y279274D01*
X146146D01*
Y279137D01*
X146284D01*
Y279000D01*
X146421D01*
Y278862D01*
X146559D01*
Y278725D01*
X146833D01*
Y278588D01*
X147108D01*
Y278450D01*
X147382D01*
Y278313D01*
X148618D01*
Y278176D01*
X148756D01*
Y278313D01*
X159878D01*
Y278176D01*
X160290D01*
Y278039D01*
X160565D01*
Y277901D01*
X160702D01*
Y277626D01*
X160840D01*
Y277352D01*
X160977D01*
Y263895D01*
X160840D01*
Y263483D01*
X160702D01*
Y263346D01*
X160565D01*
Y263208D01*
X160427D01*
Y263071D01*
X160290D01*
Y262934D01*
X151914D01*
Y262796D01*
X151365D01*
Y262659D01*
X151227D01*
Y262522D01*
X151090D01*
Y262384D01*
X150953D01*
Y262247D01*
X150815D01*
Y261835D01*
X150678D01*
Y261423D01*
X150815D01*
Y261011D01*
X150953D01*
Y260737D01*
X151090D01*
Y260599D01*
X151365D01*
Y260462D01*
X151777D01*
Y260324D01*
X160153D01*
Y260187D01*
X160427D01*
Y260050D01*
X160565D01*
Y259913D01*
X160702D01*
Y259775D01*
X160840D01*
Y259363D01*
X160977D01*
Y233136D01*
X160840D01*
Y232861D01*
X160702D01*
Y232586D01*
X160565D01*
Y232449D01*
X160290D01*
Y232312D01*
X160016D01*
Y232174D01*
X146421D01*
Y232037D01*
X146146D01*
Y231900D01*
X146009D01*
Y231763D01*
X145872D01*
Y231625D01*
X145735D01*
Y231350D01*
X145597D01*
Y132482D01*
X145460D01*
Y131933D01*
X145323D01*
Y131521D01*
X145185D01*
Y131246D01*
X145048D01*
Y130971D01*
X144911D01*
Y130697D01*
X144773D01*
Y130422D01*
X144636D01*
Y130285D01*
X144499D01*
Y130010D01*
X144361D01*
Y129873D01*
X144224D01*
Y129736D01*
X144087D01*
Y129461D01*
X143949D01*
Y129324D01*
X143812D01*
Y129186D01*
X143675D01*
Y129049D01*
X143538D01*
Y128912D01*
X143400D01*
Y128774D01*
X143263D01*
Y128637D01*
X143125D01*
Y128500D01*
X142988D01*
Y128362D01*
X142851D01*
Y128225D01*
X142714D01*
Y128088D01*
X142439D01*
Y127950D01*
X142302D01*
Y127813D01*
X142164D01*
Y127676D01*
X141890D01*
Y127538D01*
X141752D01*
Y127401D01*
X141478D01*
Y127264D01*
X141340D01*
Y127127D01*
X141066D01*
Y126989D01*
X140791D01*
Y126852D01*
X140517D01*
Y126715D01*
X140105D01*
Y126577D01*
X139693D01*
Y126440D01*
X139281D01*
Y126303D01*
X138869D01*
Y126165D01*
X138182D01*
Y126028D01*
X136809D01*
Y125891D01*
X136534D01*
Y126028D01*
X135298D01*
Y126165D01*
X134474D01*
Y126303D01*
X134063D01*
Y126440D01*
X133651D01*
Y126577D01*
X133239D01*
Y126715D01*
X132964D01*
Y126852D01*
X132689D01*
Y126989D01*
X132415D01*
Y127127D01*
X132140D01*
Y127264D01*
X132003D01*
Y127401D01*
X131728D01*
Y127538D01*
X131591D01*
Y127676D01*
X131316D01*
Y127813D01*
X131179D01*
Y127950D01*
X131042D01*
Y128088D01*
X130904D01*
Y128225D01*
X130630D01*
Y128362D01*
X130492D01*
Y128500D01*
X130355D01*
Y128637D01*
X130218D01*
Y128774D01*
X130080D01*
Y128912D01*
X129943D01*
Y129186D01*
X129806D01*
Y129324D01*
X129668D01*
Y129461D01*
X129531D01*
Y129598D01*
X129394D01*
Y129873D01*
X129256D01*
Y130010D01*
X129119D01*
Y130285D01*
X128982D01*
Y130560D01*
X128844D01*
Y130697D01*
X128707D01*
Y130971D01*
X128570D01*
Y131246D01*
X128433D01*
Y131658D01*
X128295D01*
Y132070D01*
X128158D01*
Y132482D01*
X128021D01*
Y132894D01*
X127883D01*
Y133581D01*
X127746D01*
Y162005D01*
X127609D01*
Y163241D01*
X127471D01*
Y163928D01*
X127334D01*
Y164477D01*
X127197D01*
Y164752D01*
X127059D01*
Y165163D01*
X126922D01*
Y165438D01*
X126785D01*
Y165713D01*
X126647D01*
Y165987D01*
X126510D01*
Y166262D01*
X126373D01*
Y166537D01*
X126236D01*
Y166674D01*
X126098D01*
Y166949D01*
X125961D01*
Y167086D01*
X125823D01*
Y167223D01*
X125686D01*
Y167498D01*
X125549D01*
Y167635D01*
X125412D01*
Y167773D01*
X125274D01*
Y167910D01*
X125137D01*
Y168047D01*
X125000D01*
Y168185D01*
X124862D01*
Y168322D01*
X124725D01*
Y168459D01*
X124588D01*
Y168596D01*
X124450D01*
Y168734D01*
X124176D01*
Y168871D01*
X124038D01*
Y169008D01*
X123901D01*
Y169146D01*
X123626D01*
Y169283D01*
X123489D01*
Y169420D01*
X123215D01*
Y169558D01*
X122940D01*
Y169695D01*
X122665D01*
Y169832D01*
X122391D01*
Y169970D01*
X122116D01*
Y170107D01*
X121704D01*
Y170244D01*
X121292D01*
Y170382D01*
X120880D01*
Y170519D01*
X120194D01*
Y170656D01*
X117310D01*
Y170519D01*
X116623D01*
Y170382D01*
X116211D01*
Y170244D01*
X115799D01*
Y170107D01*
X115387D01*
Y169970D01*
X115113D01*
Y169832D01*
X114838D01*
Y169695D01*
X114564D01*
Y169558D01*
X114289D01*
Y169420D01*
X114151D01*
Y169283D01*
X113877D01*
Y169146D01*
X113740D01*
Y169008D01*
X113465D01*
Y168871D01*
X113328D01*
Y168734D01*
X113190D01*
Y168596D01*
X113053D01*
Y168459D01*
X112778D01*
Y168322D01*
X112641D01*
Y168185D01*
X112504D01*
Y168047D01*
X112366D01*
Y167910D01*
X112229D01*
Y167773D01*
X112092D01*
Y167498D01*
X111954D01*
Y167361D01*
X111817D01*
Y167223D01*
X111680D01*
Y167086D01*
X111543D01*
Y166811D01*
X111405D01*
Y166674D01*
X111268D01*
Y166399D01*
X111131D01*
Y166125D01*
X110993D01*
Y165987D01*
X110856D01*
Y165713D01*
X110719D01*
Y165438D01*
X110581D01*
Y165026D01*
X110444D01*
Y164752D01*
X110307D01*
Y164340D01*
X110169D01*
Y163790D01*
X110032D01*
Y163104D01*
X109895D01*
Y161731D01*
X109757D01*
Y161593D01*
X109895D01*
Y120398D01*
X109757D01*
Y120261D01*
X109895D01*
Y119986D01*
X109757D01*
Y119025D01*
X109620D01*
Y118338D01*
X109483D01*
Y117926D01*
X109345D01*
Y117514D01*
X109208D01*
Y117102D01*
X109071D01*
Y116828D01*
X108933D01*
Y116553D01*
X108796D01*
Y116278D01*
X108659D01*
Y116004D01*
X108521D01*
Y115866D01*
X108384D01*
Y115592D01*
X108247D01*
Y115455D01*
X108110D01*
Y115180D01*
X107972D01*
Y115043D01*
X107835D01*
Y114905D01*
X107698D01*
Y114631D01*
X107560D01*
Y114493D01*
X107423D01*
Y114356D01*
X107286D01*
Y114219D01*
X107148D01*
Y114081D01*
X107011D01*
Y113944D01*
X106874D01*
Y113807D01*
X106736D01*
Y113669D01*
X106462D01*
Y113532D01*
X106324D01*
Y113395D01*
X106187D01*
Y113258D01*
X106050D01*
Y113120D01*
X105775D01*
Y112983D01*
X105638D01*
Y112845D01*
X105363D01*
Y112708D01*
X105089D01*
Y112571D01*
X104814D01*
Y112434D01*
X104539D01*
Y112296D01*
X104265D01*
Y112159D01*
X103853D01*
Y112022D01*
X103441D01*
Y111884D01*
X103029D01*
Y111747D01*
X102342D01*
Y111610D01*
X99459D01*
Y111747D01*
X98772D01*
Y111884D01*
X98223D01*
Y112022D01*
X97811D01*
Y112159D01*
X97536D01*
Y112296D01*
X97124D01*
Y112434D01*
X96849D01*
Y112571D01*
X96575D01*
Y112708D01*
X96438D01*
Y112845D01*
X96163D01*
Y112983D01*
X95888D01*
Y113120D01*
X95751D01*
Y113258D01*
X95614D01*
Y113395D01*
X95339D01*
Y113532D01*
X95202D01*
Y113669D01*
X95064D01*
Y113807D01*
X94927D01*
Y113944D01*
X94790D01*
Y114081D01*
X94652D01*
Y114219D01*
X94515D01*
Y114356D01*
X94378D01*
Y114493D01*
X94241D01*
Y114631D01*
X94103D01*
Y114768D01*
X93966D01*
Y114905D01*
X93828D01*
Y115180D01*
X93691D01*
Y115317D01*
X93554D01*
Y115455D01*
X93417D01*
Y115729D01*
X93279D01*
Y115866D01*
X93142D01*
Y116141D01*
X93005D01*
Y116416D01*
X92867D01*
Y116690D01*
X92730D01*
Y116965D01*
X92593D01*
Y117377D01*
X92455D01*
Y117789D01*
X92318D01*
Y118201D01*
X92181D01*
Y118750D01*
X92043D01*
Y119437D01*
X91906D01*
Y145802D01*
X91769D01*
Y146763D01*
X91631D01*
Y147312D01*
X91494D01*
Y147724D01*
X91357D01*
Y148136D01*
X91220D01*
Y148411D01*
X91082D01*
Y148823D01*
X90945D01*
Y149097D01*
X90808D01*
Y149235D01*
X90670D01*
Y149509D01*
X90533D01*
Y149784D01*
X90396D01*
Y149921D01*
X90258D01*
Y150196D01*
X90121D01*
Y150333D01*
X89984D01*
Y150471D01*
X89846D01*
Y150745D01*
X89709D01*
Y150883D01*
X89572D01*
Y151020D01*
X89434D01*
Y151157D01*
X89297D01*
Y151294D01*
X89160D01*
Y151432D01*
X89022D01*
Y151569D01*
X88885D01*
Y151706D01*
X88748D01*
Y151844D01*
X88610D01*
Y151981D01*
X88336D01*
Y152118D01*
X88198D01*
Y152256D01*
X88061D01*
Y152393D01*
X87787D01*
Y152530D01*
X87649D01*
Y152668D01*
X87375D01*
Y152805D01*
X87100D01*
Y152942D01*
X86825D01*
Y153080D01*
X86551D01*
Y153217D01*
X86276D01*
Y153354D01*
X85864D01*
Y153491D01*
X85452D01*
Y153629D01*
X84903D01*
Y153766D01*
X84079D01*
Y153904D01*
X81882D01*
Y153766D01*
X81058D01*
Y153629D01*
X80509D01*
Y153491D01*
X80097D01*
Y153354D01*
X79685D01*
Y153217D01*
X79410D01*
Y153080D01*
X79136D01*
Y152942D01*
X78861D01*
Y152805D01*
X78586D01*
Y152668D01*
X78312D01*
Y152530D01*
X78174D01*
Y152393D01*
X77900D01*
Y152256D01*
X77762D01*
Y152118D01*
X77488D01*
Y151981D01*
X77350D01*
Y151844D01*
X77213D01*
Y151706D01*
X77076D01*
Y151569D01*
X76939D01*
Y151432D01*
X76801D01*
Y151294D01*
X76664D01*
Y151157D01*
X76526D01*
Y151020D01*
X76389D01*
Y150883D01*
X76252D01*
Y150745D01*
X76115D01*
Y150608D01*
X75977D01*
Y150333D01*
X75840D01*
Y150196D01*
X75703D01*
Y150059D01*
X75565D01*
Y149784D01*
X75428D01*
Y149647D01*
X75291D01*
Y149372D01*
X75153D01*
Y149097D01*
X75016D01*
Y148823D01*
X74879D01*
Y148548D01*
X74741D01*
Y148136D01*
X74604D01*
Y147861D01*
X74467D01*
Y147312D01*
X74329D01*
Y146763D01*
X74192D01*
Y145939D01*
X74055D01*
Y74671D01*
X73917D01*
Y73847D01*
X73780D01*
Y73298D01*
X73643D01*
Y72886D01*
X73506D01*
Y72474D01*
X73368D01*
Y72200D01*
X73231D01*
Y71925D01*
X73094D01*
Y71513D01*
X72956D01*
Y71376D01*
X72819D01*
Y71101D01*
X72682D01*
Y70826D01*
X72544D01*
Y70689D01*
X72407D01*
Y70414D01*
X72270D01*
Y70277D01*
X72132D01*
Y70140D01*
X71995D01*
Y69865D01*
X71858D01*
Y69728D01*
X71720D01*
Y69591D01*
X71583D01*
Y69453D01*
X71446D01*
Y69316D01*
X71308D01*
Y69179D01*
X71171D01*
Y69041D01*
X71034D01*
Y68904D01*
X70897D01*
Y68767D01*
X70622D01*
Y68629D01*
X70485D01*
Y68492D01*
X70347D01*
Y68355D01*
X70210D01*
Y68217D01*
X69935D01*
Y68080D01*
X69798D01*
Y67943D01*
X69523D01*
Y67805D01*
X69249D01*
Y67668D01*
X68974D01*
Y67531D01*
X68699D01*
Y67393D01*
X68425D01*
Y67256D01*
X68013D01*
Y67119D01*
X67601D01*
Y66982D01*
X67052D01*
Y66844D01*
X66365D01*
Y66707D01*
X63756D01*
Y66844D01*
X63069D01*
Y66982D01*
X62520D01*
Y67119D01*
X62108D01*
Y67256D01*
X61834D01*
Y67393D01*
X61422D01*
Y67531D01*
X61147D01*
Y67668D01*
X60872D01*
Y67805D01*
X60598D01*
Y67943D01*
X60460D01*
Y68080D01*
X60186D01*
Y68217D01*
X60048D01*
Y68355D01*
X59774D01*
Y68492D01*
X59637D01*
Y68629D01*
X59499D01*
Y68767D01*
X59362D01*
Y68904D01*
X59087D01*
Y69041D01*
X58950D01*
Y69179D01*
X58813D01*
Y69316D01*
X58675D01*
Y69453D01*
X58538D01*
Y69591D01*
X58401D01*
Y69865D01*
X58263D01*
Y70002D01*
X58126D01*
Y70140D01*
X57989D01*
Y70277D01*
X57851D01*
Y70552D01*
X57714D01*
Y70689D01*
X57577D01*
Y70964D01*
X57439D01*
Y71101D01*
X57302D01*
Y71376D01*
X57165D01*
Y71650D01*
X57027D01*
Y71925D01*
X56890D01*
Y72200D01*
X56753D01*
Y72611D01*
X56616D01*
Y73024D01*
X56478D01*
Y73435D01*
X56341D01*
Y73985D01*
X56203D01*
Y74946D01*
X56066D01*
Y75083D01*
X56203D01*
Y75220D01*
X56066D01*
Y183839D01*
X55929D01*
Y184525D01*
X55792D01*
Y185075D01*
X55654D01*
Y185487D01*
X55517D01*
Y185898D01*
X55380D01*
Y186173D01*
X55242D01*
Y186448D01*
X55105D01*
Y186722D01*
X54968D01*
Y186997D01*
X54830D01*
Y187272D01*
X54693D01*
Y187409D01*
X54556D01*
Y187684D01*
X54418D01*
Y187821D01*
X54281D01*
Y188095D01*
X54144D01*
Y188233D01*
X54007D01*
Y188370D01*
X53869D01*
Y188507D01*
X53732D01*
Y188645D01*
X53594D01*
Y188782D01*
X53457D01*
Y188919D01*
X53320D01*
Y189057D01*
X53183D01*
Y189194D01*
X53045D01*
Y189331D01*
X52908D01*
Y189469D01*
X52771D01*
Y189606D01*
X52633D01*
Y189743D01*
X52359D01*
Y189881D01*
X52221D01*
Y190018D01*
X51947D01*
Y190155D01*
X51809D01*
Y190293D01*
X51535D01*
Y190430D01*
X51260D01*
Y190567D01*
X50985D01*
Y190705D01*
X50711D01*
Y190842D01*
X50436D01*
Y190979D01*
X50024D01*
Y191117D01*
X49612D01*
Y191254D01*
X49063D01*
Y191391D01*
X48239D01*
Y191528D01*
X46042D01*
Y191391D01*
X45218D01*
Y191254D01*
X44669D01*
Y191117D01*
X44257D01*
Y190979D01*
X43982D01*
Y190842D01*
X43570D01*
Y190705D01*
X43296D01*
Y190567D01*
X43021D01*
Y190430D01*
X42746D01*
Y190293D01*
X42609D01*
Y190155D01*
X42334D01*
Y190018D01*
X42197D01*
Y189881D01*
X41922D01*
Y189743D01*
X41785D01*
Y189606D01*
X41648D01*
Y189469D01*
X41373D01*
Y189331D01*
X41236D01*
Y189194D01*
X41099D01*
Y189057D01*
X40961D01*
Y188919D01*
X40824D01*
Y188782D01*
X40687D01*
Y188645D01*
X40549D01*
Y188507D01*
X40412D01*
Y188233D01*
X40275D01*
Y188095D01*
X40137D01*
Y187958D01*
X40000D01*
Y187821D01*
X39863D01*
Y187546D01*
X39725D01*
Y187272D01*
X39588D01*
Y187134D01*
X39451D01*
Y186860D01*
X39313D01*
Y186585D01*
X39176D01*
Y186310D01*
X39039D01*
Y186036D01*
X38902D01*
Y185624D01*
X38764D01*
Y185349D01*
X38627D01*
Y184800D01*
X38490D01*
Y184251D01*
X38352D01*
Y183152D01*
X38215D01*
Y162417D01*
X38078D01*
Y161593D01*
X37940D01*
Y161181D01*
X37803D01*
Y160632D01*
X37666D01*
Y160357D01*
X37528D01*
Y159945D01*
X37391D01*
Y159671D01*
X37254D01*
Y159396D01*
X37116D01*
Y159122D01*
X36979D01*
Y158984D01*
X36842D01*
Y158710D01*
X36704D01*
Y158572D01*
X36567D01*
Y158298D01*
X36430D01*
Y158160D01*
X36293D01*
Y158023D01*
X36155D01*
Y157748D01*
X36018D01*
Y157611D01*
X35880D01*
Y157474D01*
X35743D01*
Y157336D01*
X35606D01*
Y157199D01*
X35469D01*
Y157062D01*
X35331D01*
Y156924D01*
X35194D01*
Y156787D01*
X35057D01*
Y156650D01*
X34782D01*
Y156512D01*
X34645D01*
Y156375D01*
X34507D01*
Y156238D01*
X34233D01*
Y156101D01*
X34095D01*
Y155963D01*
X33821D01*
Y155826D01*
X33684D01*
Y155689D01*
X33409D01*
Y155551D01*
X33134D01*
Y155414D01*
X32860D01*
Y155277D01*
X32448D01*
Y155139D01*
X32036D01*
Y155002D01*
X31624D01*
Y154865D01*
X31074D01*
Y154727D01*
X30113D01*
Y154590D01*
X29976D01*
Y154727D01*
X29839D01*
Y154590D01*
X28328D01*
Y154727D01*
X27504D01*
Y154865D01*
X26955D01*
Y155002D01*
X26543D01*
Y155139D01*
X26131D01*
Y155277D01*
X25719D01*
Y155414D01*
X25444D01*
Y155551D01*
X25170D01*
Y155689D01*
X24895D01*
Y155826D01*
X24758D01*
Y155963D01*
X24483D01*
Y156101D01*
X24209D01*
Y156238D01*
X24071D01*
Y156375D01*
X23934D01*
Y156512D01*
X23659D01*
Y156650D01*
X23522D01*
Y156787D01*
X23385D01*
Y156924D01*
X23247D01*
Y157062D01*
X23110D01*
Y157199D01*
X22973D01*
Y157336D01*
X22835D01*
Y157474D01*
X22698D01*
Y157611D01*
X22561D01*
Y157748D01*
X22423D01*
Y157886D01*
X22286D01*
Y158160D01*
X22149D01*
Y158298D01*
X22011D01*
Y158435D01*
X21874D01*
Y158710D01*
X21737D01*
Y158847D01*
X21600D01*
Y159122D01*
X21462D01*
Y159396D01*
X21325D01*
Y159671D01*
X21188D01*
Y159945D01*
X21050D01*
Y160220D01*
X20913D01*
Y160632D01*
X20776D01*
Y161044D01*
X20638D01*
Y161593D01*
X20501D01*
Y162143D01*
X20364D01*
Y163653D01*
X20226D01*
Y336948D01*
X20364D01*
Y337085D01*
X75153D01*
Y323765D01*
X90258D01*
Y336948D01*
X90396D01*
Y337085D01*
X93691D01*
Y323765D01*
X108933D01*
Y337085D01*
X112229D01*
Y336948D01*
X112366D01*
Y323765D01*
X127471D01*
Y337085D01*
X130904D01*
Y323765D01*
X146009D01*
Y337085D01*
X158368D01*
Y316625D01*
D02*
G37*
G36*
X30250Y141819D02*
X30937D01*
Y141682D01*
X31624D01*
Y141545D01*
X32036D01*
Y141408D01*
X32448D01*
Y141270D01*
X32860D01*
Y141133D01*
X33134D01*
Y140996D01*
X33409D01*
Y140858D01*
X33684D01*
Y140721D01*
X33821D01*
Y140584D01*
X34095D01*
Y140446D01*
X34370D01*
Y140309D01*
X34507D01*
Y140172D01*
X34645D01*
Y140034D01*
X34919D01*
Y139897D01*
X35057D01*
Y139760D01*
X35194D01*
Y139622D01*
X35331D01*
Y139485D01*
X35469D01*
Y139348D01*
X35606D01*
Y139211D01*
X35743D01*
Y139073D01*
X35880D01*
Y138936D01*
X36018D01*
Y138799D01*
X36155D01*
Y138661D01*
X36293D01*
Y138524D01*
X36430D01*
Y138249D01*
X36567D01*
Y138112D01*
X36704D01*
Y137837D01*
X36842D01*
Y137700D01*
X36979D01*
Y137425D01*
X37116D01*
Y137151D01*
X37254D01*
Y137013D01*
X37391D01*
Y136601D01*
X37528D01*
Y136327D01*
X37666D01*
Y135915D01*
X37803D01*
Y135503D01*
X37940D01*
Y135091D01*
X38078D01*
Y134404D01*
X38215D01*
Y121085D01*
X38078D01*
Y120398D01*
X37940D01*
Y119849D01*
X37803D01*
Y119437D01*
X37666D01*
Y119025D01*
X37528D01*
Y118750D01*
X37391D01*
Y118476D01*
X37254D01*
Y118201D01*
X37116D01*
Y117926D01*
X36979D01*
Y117652D01*
X36842D01*
Y117514D01*
X36704D01*
Y117240D01*
X36567D01*
Y117102D01*
X36430D01*
Y116965D01*
X36293D01*
Y116828D01*
X36155D01*
Y116553D01*
X36018D01*
Y116416D01*
X35880D01*
Y116278D01*
X35743D01*
Y116141D01*
X35606D01*
Y116004D01*
X35469D01*
Y115866D01*
X35331D01*
Y115729D01*
X35194D01*
Y115592D01*
X35057D01*
Y115455D01*
X34782D01*
Y115317D01*
X34645D01*
Y115180D01*
X34507D01*
Y115043D01*
X34233D01*
Y114905D01*
X34095D01*
Y114768D01*
X33821D01*
Y114631D01*
X33546D01*
Y114493D01*
X33272D01*
Y114356D01*
X32997D01*
Y114219D01*
X32722D01*
Y114081D01*
X32310D01*
Y113944D01*
X31898D01*
Y113807D01*
X31486D01*
Y113669D01*
X30800D01*
Y113532D01*
X29564D01*
Y113395D01*
X29015D01*
Y113532D01*
X27641D01*
Y113669D01*
X27092D01*
Y113807D01*
X26543D01*
Y113944D01*
X26131D01*
Y114081D01*
X25856D01*
Y114219D01*
X25444D01*
Y114356D01*
X25170D01*
Y114493D01*
X25032D01*
Y114631D01*
X24758D01*
Y114768D01*
X24483D01*
Y114905D01*
X24346D01*
Y115043D01*
X24071D01*
Y115180D01*
X23934D01*
Y115317D01*
X23659D01*
Y115455D01*
X23522D01*
Y115592D01*
X23385D01*
Y115729D01*
X23247D01*
Y115866D01*
X23110D01*
Y116004D01*
X22973D01*
Y116141D01*
X22835D01*
Y116278D01*
X22698D01*
Y116416D01*
X22561D01*
Y116553D01*
X22423D01*
Y116690D01*
X22286D01*
Y116828D01*
X22149D01*
Y117102D01*
X22011D01*
Y117240D01*
X21874D01*
Y117514D01*
X21737D01*
Y117652D01*
X21600D01*
Y117926D01*
X21462D01*
Y118201D01*
X21325D01*
Y118338D01*
X21188D01*
Y118750D01*
X21050D01*
Y119025D01*
X20913D01*
Y119437D01*
X20776D01*
Y119711D01*
X20638D01*
Y120261D01*
X20501D01*
Y120947D01*
X20364D01*
Y122320D01*
X20226D01*
Y122458D01*
X20364D01*
Y122595D01*
X20226D01*
Y133031D01*
X20364D01*
Y134542D01*
X20501D01*
Y135091D01*
X20638D01*
Y135640D01*
X20776D01*
Y136052D01*
X20913D01*
Y136327D01*
X21050D01*
Y136739D01*
X21188D01*
Y137013D01*
X21325D01*
Y137288D01*
X21462D01*
Y137563D01*
X21600D01*
Y137700D01*
X21737D01*
Y137975D01*
X21874D01*
Y138112D01*
X22011D01*
Y138387D01*
X22149D01*
Y138524D01*
X22286D01*
Y138661D01*
X22423D01*
Y138799D01*
X22561D01*
Y138936D01*
X22698D01*
Y139073D01*
X22835D01*
Y139211D01*
X22973D01*
Y139348D01*
X23110D01*
Y139485D01*
X23247D01*
Y139622D01*
X23385D01*
Y139760D01*
X23522D01*
Y139897D01*
X23659D01*
Y140034D01*
X23797D01*
Y140172D01*
X24071D01*
Y140309D01*
X24209D01*
Y140446D01*
X24483D01*
Y140584D01*
X24620D01*
Y140721D01*
X24895D01*
Y140858D01*
X25170D01*
Y140996D01*
X25444D01*
Y141133D01*
X25719D01*
Y141270D01*
X26131D01*
Y141408D01*
X26406D01*
Y141545D01*
X26955D01*
Y141682D01*
X27504D01*
Y141819D01*
X28465D01*
Y141957D01*
X30250D01*
Y141819D01*
D02*
G37*
G36*
X102205Y100899D02*
X102892D01*
Y100762D01*
X103441D01*
Y100624D01*
X103853D01*
Y100487D01*
X104127D01*
Y100350D01*
X104539D01*
Y100212D01*
X104814D01*
Y100075D01*
X105089D01*
Y99938D01*
X105226D01*
Y99800D01*
X105500D01*
Y99663D01*
X105775D01*
Y99526D01*
X105913D01*
Y99388D01*
X106187D01*
Y99251D01*
X106324D01*
Y99114D01*
X106462D01*
Y98976D01*
X106599D01*
Y98839D01*
X106874D01*
Y98702D01*
X107011D01*
Y98565D01*
X107148D01*
Y98427D01*
X107286D01*
Y98290D01*
X107423D01*
Y98153D01*
X107560D01*
Y97878D01*
X107698D01*
Y97741D01*
X107835D01*
Y97603D01*
X107972D01*
Y97466D01*
X108110D01*
Y97191D01*
X108247D01*
Y97054D01*
X108384D01*
Y96779D01*
X108521D01*
Y96642D01*
X108659D01*
Y96367D01*
X108796D01*
Y96093D01*
X108933D01*
Y95818D01*
X109071D01*
Y95543D01*
X109208D01*
Y95132D01*
X109345D01*
Y94720D01*
X109483D01*
Y94308D01*
X109620D01*
Y93621D01*
X109757D01*
Y92660D01*
X109895D01*
Y91699D01*
X109757D01*
Y91561D01*
X109895D01*
Y91424D01*
X109757D01*
Y91287D01*
X109895D01*
Y91149D01*
X109757D01*
Y90325D01*
X109620D01*
Y89639D01*
X109483D01*
Y89090D01*
X109345D01*
Y88678D01*
X109208D01*
Y88403D01*
X109071D01*
Y87991D01*
X108933D01*
Y87716D01*
X108796D01*
Y87442D01*
X108659D01*
Y87304D01*
X108521D01*
Y87030D01*
X108384D01*
Y86755D01*
X108247D01*
Y86618D01*
X108110D01*
Y86481D01*
X107972D01*
Y86206D01*
X107835D01*
Y86069D01*
X107698D01*
Y85931D01*
X107560D01*
Y85794D01*
X107423D01*
Y85657D01*
X107286D01*
Y85519D01*
X107148D01*
Y85382D01*
X107011D01*
Y85245D01*
X106874D01*
Y85107D01*
X106736D01*
Y84970D01*
X106599D01*
Y84833D01*
X106462D01*
Y84695D01*
X106324D01*
Y84558D01*
X106050D01*
Y84421D01*
X105913D01*
Y84284D01*
X105638D01*
Y84146D01*
X105500D01*
Y84009D01*
X105226D01*
Y83871D01*
X104951D01*
Y83734D01*
X104677D01*
Y83597D01*
X104402D01*
Y83460D01*
X104127D01*
Y83322D01*
X103715D01*
Y83185D01*
X103303D01*
Y83048D01*
X102754D01*
Y82910D01*
X101930D01*
Y82773D01*
X99871D01*
Y82910D01*
X99047D01*
Y83048D01*
X98497D01*
Y83185D01*
X98085D01*
Y83322D01*
X97673D01*
Y83460D01*
X97399D01*
Y83597D01*
X96987D01*
Y83734D01*
X96712D01*
Y83871D01*
X96575D01*
Y84009D01*
X96300D01*
Y84146D01*
X96026D01*
Y84284D01*
X95888D01*
Y84421D01*
X95614D01*
Y84558D01*
X95476D01*
Y84695D01*
X95339D01*
Y84833D01*
X95064D01*
Y84970D01*
X94927D01*
Y85107D01*
X94790D01*
Y85245D01*
X94652D01*
Y85382D01*
X94515D01*
Y85519D01*
X94378D01*
Y85657D01*
X94241D01*
Y85794D01*
X94103D01*
Y86069D01*
X93966D01*
Y86206D01*
X93828D01*
Y86343D01*
X93691D01*
Y86481D01*
X93554D01*
Y86755D01*
X93417D01*
Y86892D01*
X93279D01*
Y87167D01*
X93142D01*
Y87442D01*
X93005D01*
Y87579D01*
X92867D01*
Y87854D01*
X92730D01*
Y88266D01*
X92593D01*
Y88540D01*
X92455D01*
Y88952D01*
X92318D01*
Y89364D01*
X92181D01*
Y89914D01*
X92043D01*
Y90737D01*
X91906D01*
Y93209D01*
X92043D01*
Y93896D01*
X92181D01*
Y94445D01*
X92318D01*
Y94857D01*
X92455D01*
Y95269D01*
X92593D01*
Y95681D01*
X92730D01*
Y95955D01*
X92867D01*
Y96230D01*
X93005D01*
Y96505D01*
X93142D01*
Y96642D01*
X93279D01*
Y96917D01*
X93417D01*
Y97054D01*
X93554D01*
Y97329D01*
X93691D01*
Y97466D01*
X93828D01*
Y97741D01*
X93966D01*
Y97878D01*
X94103D01*
Y98015D01*
X94241D01*
Y98153D01*
X94378D01*
Y98290D01*
X94515D01*
Y98427D01*
X94652D01*
Y98565D01*
X94790D01*
Y98702D01*
X94927D01*
Y98839D01*
X95064D01*
Y98976D01*
X95202D01*
Y99114D01*
X95476D01*
Y99251D01*
X95614D01*
Y99388D01*
X95751D01*
Y99526D01*
X96026D01*
Y99663D01*
X96163D01*
Y99800D01*
X96438D01*
Y99938D01*
X96712D01*
Y100075D01*
X96987D01*
Y100212D01*
X97261D01*
Y100350D01*
X97536D01*
Y100487D01*
X97948D01*
Y100624D01*
X98360D01*
Y100762D01*
X98909D01*
Y100899D01*
X99596D01*
Y101036D01*
X102205D01*
Y100899D01*
D02*
G37*
G36*
X206589Y301958D02*
X206829Y301915D01*
X207041Y301887D01*
X207238Y301831D01*
X207407Y301775D01*
X207576Y301718D01*
X207717Y301662D01*
X207844Y301591D01*
X207957Y301535D01*
X208055Y301478D01*
X208126Y301422D01*
X208182Y301380D01*
X208239Y301352D01*
X208253Y301337D01*
X208267Y301323D01*
X208394Y301182D01*
X208507Y301041D01*
X208605Y300886D01*
X208690Y300717D01*
X208817Y300393D01*
X208901Y300083D01*
X208958Y299787D01*
X208972Y299674D01*
X208986Y299561D01*
X209000Y299477D01*
Y299350D01*
X208986Y299040D01*
X208944Y298758D01*
X208887Y298504D01*
X208817Y298278D01*
X208760Y298095D01*
X208704Y297968D01*
X208662Y297884D01*
X208648Y297855D01*
X208507Y297630D01*
X208337Y297433D01*
X208168Y297278D01*
X208013Y297136D01*
X207858Y297038D01*
X207745Y296967D01*
X207661Y296925D01*
X207647Y296911D01*
X207633D01*
X207351Y296812D01*
X207055Y296728D01*
X206730Y296671D01*
X206420Y296643D01*
X206152Y296615D01*
X206040D01*
X205927Y296601D01*
X205842D01*
X205786D01*
X205744D01*
X205730D01*
X199076D01*
Y297898D01*
X205800D01*
X206096D01*
X206350Y297926D01*
X206561Y297940D01*
X206730Y297968D01*
X206857Y297997D01*
X206956Y298011D01*
X207012Y298039D01*
X207026D01*
X207167Y298095D01*
X207280Y298166D01*
X207379Y298250D01*
X207477Y298321D01*
X207534Y298405D01*
X207590Y298462D01*
X207619Y298504D01*
X207633Y298518D01*
X207703Y298659D01*
X207759Y298800D01*
X207788Y298941D01*
X207816Y299068D01*
X207830Y299195D01*
X207844Y299279D01*
Y299364D01*
X207830Y299589D01*
X207773Y299801D01*
X207717Y299970D01*
X207633Y300125D01*
X207562Y300238D01*
X207492Y300322D01*
X207449Y300379D01*
X207435Y300393D01*
X207351Y300463D01*
X207252Y300520D01*
X207026Y300604D01*
X206773Y300689D01*
X206519Y300731D01*
X206279Y300774D01*
X206181D01*
X206096Y300788D01*
X206011Y300802D01*
X205955D01*
X205927D01*
X205913D01*
X206082Y301972D01*
X206350D01*
X206589Y301958D01*
D02*
G37*
G36*
X196800Y300633D02*
X193840Y299575D01*
Y295487D01*
X196800Y294345D01*
Y292879D01*
X187045Y296869D01*
Y298278D01*
X196800Y302000D01*
Y300633D01*
D02*
G37*
G36*
X206646Y294655D02*
X206829Y294641D01*
X206998Y294627D01*
X207111D01*
X207196Y294613D01*
X207252Y294599D01*
X207266D01*
X207449Y294557D01*
X207619Y294500D01*
X207773Y294444D01*
X207900Y294373D01*
X208013Y294317D01*
X208084Y294275D01*
X208140Y294247D01*
X208154Y294233D01*
X208281Y294120D01*
X208394Y293993D01*
X208493Y293866D01*
X208577Y293725D01*
X208648Y293612D01*
X208704Y293514D01*
X208732Y293457D01*
X208746Y293429D01*
X208831Y293218D01*
X208887Y293020D01*
X208930Y292823D01*
X208958Y292640D01*
X208972Y292484D01*
X208986Y292358D01*
Y292259D01*
X208972Y292005D01*
X208930Y291751D01*
X208873Y291526D01*
X208803Y291300D01*
X208704Y291103D01*
X208605Y290920D01*
X208507Y290751D01*
X208394Y290595D01*
X208281Y290455D01*
X208182Y290342D01*
X208070Y290243D01*
X207985Y290159D01*
X207915Y290088D01*
X207858Y290046D01*
X207816Y290018D01*
X207802Y290004D01*
X208831D01*
Y288932D01*
X201754D01*
Y290130D01*
X205546D01*
X205870Y290144D01*
X206152Y290159D01*
X206392Y290187D01*
X206589Y290229D01*
X206744Y290271D01*
X206857Y290299D01*
X206914Y290314D01*
X206942Y290328D01*
X207111Y290412D01*
X207252Y290511D01*
X207379Y290624D01*
X207492Y290737D01*
X207576Y290835D01*
X207633Y290920D01*
X207675Y290976D01*
X207689Y291004D01*
X207773Y291188D01*
X207844Y291371D01*
X207886Y291540D01*
X207929Y291695D01*
X207943Y291822D01*
X207957Y291921D01*
Y292019D01*
X207943Y292217D01*
X207915Y292386D01*
X207872Y292541D01*
X207816Y292668D01*
X207773Y292781D01*
X207731Y292851D01*
X207703Y292907D01*
X207689Y292922D01*
X207576Y293048D01*
X207463Y293147D01*
X207337Y293232D01*
X207224Y293302D01*
X207111Y293344D01*
X207026Y293373D01*
X206970Y293401D01*
X206956D01*
X206801Y293429D01*
X206618Y293443D01*
X206406Y293457D01*
X206195D01*
X205997Y293471D01*
X205842D01*
X205772D01*
X205730D01*
X205701D01*
X205687D01*
X201754D01*
Y294670D01*
X206138D01*
X206406D01*
X206646Y294655D01*
D02*
G37*
G36*
X196800Y290807D02*
X193107D01*
X192825Y290793D01*
X192571Y290779D01*
X192332Y290751D01*
X192120Y290708D01*
X191951Y290666D01*
X191824Y290638D01*
X191740Y290624D01*
X191711Y290610D01*
X191556Y290553D01*
X191430Y290483D01*
X191317Y290412D01*
X191218Y290342D01*
X191147Y290271D01*
X191091Y290229D01*
X191063Y290187D01*
X191049Y290173D01*
X190964Y290060D01*
X190908Y289933D01*
X190866Y289806D01*
X190837Y289707D01*
X190823Y289609D01*
X190809Y289538D01*
Y289468D01*
X190823Y289313D01*
X190851Y289158D01*
X190894Y289003D01*
X190936Y288876D01*
X190978Y288763D01*
X191021Y288678D01*
X191049Y288622D01*
X191063Y288608D01*
X189963Y288171D01*
X189837Y288410D01*
X189738Y288636D01*
X189667Y288833D01*
X189611Y289017D01*
X189583Y289172D01*
X189569Y289299D01*
Y289397D01*
X189583Y289552D01*
X189611Y289693D01*
X189653Y289834D01*
X189696Y289947D01*
X189738Y290032D01*
X189780Y290116D01*
X189808Y290159D01*
X189822Y290173D01*
X189935Y290299D01*
X190076Y290426D01*
X190245Y290553D01*
X190400Y290666D01*
X190555Y290779D01*
X190682Y290849D01*
X190781Y290906D01*
X190795Y290920D01*
X189724D01*
Y292005D01*
X196800D01*
Y290807D01*
D02*
G37*
G36*
X208831Y285887D02*
X199076D01*
Y287085D01*
X208831D01*
Y285887D01*
D02*
G37*
G36*
Y282828D02*
X201754D01*
Y284026D01*
X208831D01*
Y282828D01*
D02*
G37*
G36*
X200443D02*
X199076D01*
Y284026D01*
X200443D01*
Y282828D01*
D02*
G37*
G36*
X196800Y286268D02*
X193135D01*
X192797Y286254D01*
X192501Y286240D01*
X192247Y286211D01*
X192036Y286169D01*
X191881Y286127D01*
X191768Y286099D01*
X191697Y286084D01*
X191669Y286070D01*
X191486Y285986D01*
X191331Y285887D01*
X191190Y285788D01*
X191077Y285690D01*
X190993Y285591D01*
X190936Y285521D01*
X190894Y285464D01*
X190880Y285450D01*
X190795Y285281D01*
X190725Y285126D01*
X190682Y284957D01*
X190640Y284816D01*
X190626Y284703D01*
X190612Y284604D01*
Y284520D01*
X190626Y284280D01*
X190668Y284083D01*
X190739Y283914D01*
X190809Y283787D01*
X190894Y283688D01*
X190950Y283617D01*
X191007Y283575D01*
X191021Y283561D01*
X191190Y283463D01*
X191373Y283392D01*
X191570Y283336D01*
X191768Y283307D01*
X191937Y283279D01*
X192092Y283265D01*
X192148D01*
X192177D01*
X192205D01*
X192219D01*
X196800D01*
Y282067D01*
X192698D01*
X192318Y282039D01*
X191993Y281982D01*
X191726Y281912D01*
X191500Y281813D01*
X191331Y281728D01*
X191218Y281644D01*
X191147Y281588D01*
X191119Y281574D01*
X190950Y281376D01*
X190823Y281165D01*
X190739Y280953D01*
X190668Y280756D01*
X190640Y280587D01*
X190626Y280446D01*
X190612Y280389D01*
Y280319D01*
X190626Y280164D01*
X190640Y280037D01*
X190668Y279910D01*
X190711Y279811D01*
X190753Y279713D01*
X190781Y279656D01*
X190795Y279614D01*
X190809Y279600D01*
X190894Y279487D01*
X190978Y279403D01*
X191063Y279332D01*
X191147Y279276D01*
X191218Y279233D01*
X191274Y279205D01*
X191317Y279177D01*
X191331D01*
X191458Y279135D01*
X191627Y279107D01*
X191796Y279092D01*
X191965Y279078D01*
X192120Y279064D01*
X192247D01*
X192332D01*
X192346D01*
X192360D01*
X196800D01*
Y277866D01*
X191951D01*
X191726D01*
X191528Y277894D01*
X191331Y277922D01*
X191162Y277950D01*
X190993Y277993D01*
X190851Y278049D01*
X190725Y278092D01*
X190598Y278148D01*
X190499Y278204D01*
X190400Y278247D01*
X190273Y278345D01*
X190189Y278402D01*
X190161Y278430D01*
X189963Y278655D01*
X189822Y278923D01*
X189710Y279191D01*
X189639Y279445D01*
X189597Y279685D01*
X189583Y279783D01*
Y279882D01*
X189569Y279952D01*
Y280051D01*
X189583Y280305D01*
X189625Y280530D01*
X189681Y280756D01*
X189766Y280967D01*
X189865Y281165D01*
X189963Y281348D01*
X190076Y281503D01*
X190189Y281658D01*
X190316Y281799D01*
X190429Y281912D01*
X190527Y282010D01*
X190626Y282095D01*
X190711Y282166D01*
X190767Y282208D01*
X190809Y282236D01*
X190823Y282250D01*
X190612Y282335D01*
X190429Y282447D01*
X190273Y282574D01*
X190147Y282687D01*
X190034Y282800D01*
X189963Y282885D01*
X189921Y282941D01*
X189907Y282969D01*
X189794Y283166D01*
X189710Y283378D01*
X189653Y283589D01*
X189611Y283801D01*
X189583Y283970D01*
X189569Y284125D01*
Y284252D01*
X189583Y284506D01*
X189625Y284745D01*
X189667Y284957D01*
X189724Y285140D01*
X189794Y285295D01*
X189837Y285408D01*
X189879Y285478D01*
X189893Y285506D01*
X190020Y285704D01*
X190161Y285873D01*
X190302Y286028D01*
X190443Y286155D01*
X190555Y286254D01*
X190654Y286338D01*
X190711Y286381D01*
X190739Y286395D01*
X189724D01*
Y287466D01*
X196800D01*
Y286268D01*
D02*
G37*
G36*
X207139Y281390D02*
X207280Y281376D01*
X207576Y281306D01*
X207816Y281207D01*
X208027Y281094D01*
X208197Y280981D01*
X208323Y280883D01*
X208394Y280812D01*
X208422Y280784D01*
X208605Y280530D01*
X208746Y280248D01*
X208845Y279938D01*
X208915Y279656D01*
X208958Y279403D01*
X208972Y279290D01*
Y279191D01*
X208986Y279107D01*
Y278994D01*
X208972Y278740D01*
X208944Y278486D01*
X208915Y278261D01*
X208873Y278063D01*
X208831Y277908D01*
X208789Y277781D01*
X208774Y277697D01*
X208760Y277669D01*
X208662Y277429D01*
X208535Y277203D01*
X208394Y276992D01*
X208267Y276780D01*
X208140Y276611D01*
X208041Y276484D01*
X207971Y276400D01*
X207943Y276386D01*
Y276372D01*
X208126Y276343D01*
X208295Y276315D01*
X208450Y276287D01*
X208577Y276245D01*
X208690Y276203D01*
X208760Y276174D01*
X208817Y276160D01*
X208831Y276146D01*
Y274891D01*
X208676Y274962D01*
X208521Y275032D01*
X208380Y275089D01*
X208253Y275117D01*
X208140Y275159D01*
X208055Y275173D01*
X207999Y275187D01*
X207985D01*
X207886Y275202D01*
X207759Y275216D01*
X207619D01*
X207463Y275230D01*
X207111Y275244D01*
X206759D01*
X206420Y275258D01*
X206265D01*
X206138D01*
X206026D01*
X205941D01*
X205885D01*
X205870D01*
X204263D01*
X203996D01*
X203756Y275272D01*
X203573Y275286D01*
X203418D01*
X203305Y275300D01*
X203220Y275314D01*
X203178Y275329D01*
X203164D01*
X202981Y275371D01*
X202826Y275427D01*
X202699Y275483D01*
X202572Y275554D01*
X202487Y275610D01*
X202417Y275653D01*
X202374Y275681D01*
X202360Y275695D01*
X202248Y275808D01*
X202135Y275935D01*
X202050Y276076D01*
X201966Y276217D01*
X201909Y276343D01*
X201867Y276442D01*
X201839Y276513D01*
X201825Y276541D01*
X201754Y276766D01*
X201698Y277006D01*
X201656Y277246D01*
X201627Y277485D01*
X201613Y277697D01*
X201599Y277852D01*
Y278007D01*
X201613Y278345D01*
X201641Y278641D01*
X201684Y278923D01*
X201726Y279149D01*
X201768Y279346D01*
X201810Y279487D01*
X201825Y279543D01*
X201839Y279586D01*
X201853Y279600D01*
Y279614D01*
X201952Y279854D01*
X202078Y280065D01*
X202191Y280248D01*
X202304Y280403D01*
X202417Y280516D01*
X202501Y280601D01*
X202558Y280657D01*
X202572Y280671D01*
X202755Y280798D01*
X202952Y280911D01*
X203150Y280996D01*
X203333Y281066D01*
X203516Y281122D01*
X203643Y281165D01*
X203699Y281179D01*
X203742D01*
X203756Y281193D01*
X203770D01*
X203925Y280023D01*
X203671Y279938D01*
X203446Y279854D01*
X203263Y279755D01*
X203121Y279670D01*
X203009Y279586D01*
X202938Y279515D01*
X202896Y279459D01*
X202882Y279445D01*
X202783Y279276D01*
X202713Y279078D01*
X202656Y278867D01*
X202628Y278669D01*
X202600Y278472D01*
X202586Y278331D01*
Y278190D01*
X202600Y277866D01*
X202642Y277584D01*
X202713Y277358D01*
X202783Y277161D01*
X202868Y277020D01*
X202924Y276907D01*
X202981Y276837D01*
X202995Y276823D01*
X203121Y276710D01*
X203277Y276625D01*
X203446Y276555D01*
X203615Y276513D01*
X203770Y276484D01*
X203911Y276470D01*
X203996D01*
X204010D01*
X204024D01*
X204052D01*
X204108D01*
X204207D01*
X204292Y276484D01*
X204320D01*
X204334D01*
X204376Y276625D01*
X204419Y276780D01*
X204503Y277105D01*
X204573Y277471D01*
X204644Y277810D01*
X204672Y277979D01*
X204686Y278134D01*
X204715Y278275D01*
X204729Y278388D01*
X204743Y278486D01*
Y278557D01*
X204757Y278613D01*
Y278627D01*
X204785Y278881D01*
X204827Y279092D01*
X204855Y279276D01*
X204884Y279417D01*
X204898Y279529D01*
X204926Y279614D01*
X204940Y279670D01*
Y279685D01*
X204996Y279868D01*
X205053Y280023D01*
X205123Y280178D01*
X205180Y280305D01*
X205236Y280417D01*
X205292Y280488D01*
X205321Y280544D01*
X205335Y280558D01*
X205433Y280699D01*
X205546Y280812D01*
X205659Y280925D01*
X205772Y281010D01*
X205870Y281080D01*
X205955Y281136D01*
X206011Y281165D01*
X206026Y281179D01*
X206181Y281249D01*
X206350Y281306D01*
X206505Y281348D01*
X206660Y281376D01*
X206787Y281390D01*
X206885Y281404D01*
X206942D01*
X206970D01*
X207139Y281390D01*
D02*
G37*
G36*
X195109Y276484D02*
X195250Y276470D01*
X195546Y276400D01*
X195786Y276301D01*
X195997Y276188D01*
X196166Y276076D01*
X196293Y275977D01*
X196363Y275907D01*
X196392Y275878D01*
X196575Y275625D01*
X196716Y275343D01*
X196814Y275032D01*
X196885Y274750D01*
X196927Y274497D01*
X196941Y274384D01*
Y274285D01*
X196956Y274201D01*
Y274088D01*
X196941Y273834D01*
X196913Y273580D01*
X196885Y273355D01*
X196843Y273158D01*
X196800Y273002D01*
X196758Y272876D01*
X196744Y272791D01*
X196730Y272763D01*
X196631Y272523D01*
X196504Y272298D01*
X196363Y272086D01*
X196237Y271875D01*
X196110Y271706D01*
X196011Y271579D01*
X195940Y271494D01*
X195912Y271480D01*
Y271466D01*
X196096Y271438D01*
X196265Y271409D01*
X196420Y271381D01*
X196547Y271339D01*
X196660Y271297D01*
X196730Y271269D01*
X196786Y271254D01*
X196800Y271240D01*
Y269986D01*
X196645Y270056D01*
X196490Y270127D01*
X196349Y270183D01*
X196222Y270211D01*
X196110Y270254D01*
X196025Y270268D01*
X195969Y270282D01*
X195955D01*
X195856Y270296D01*
X195729Y270310D01*
X195588D01*
X195433Y270324D01*
X195081Y270338D01*
X194728D01*
X194390Y270352D01*
X194235D01*
X194108D01*
X193995D01*
X193911D01*
X193854D01*
X193840D01*
X192233D01*
X191965D01*
X191726Y270366D01*
X191542Y270380D01*
X191387D01*
X191274Y270394D01*
X191190Y270409D01*
X191147Y270423D01*
X191133D01*
X190950Y270465D01*
X190795Y270521D01*
X190668Y270578D01*
X190541Y270648D01*
X190457Y270705D01*
X190386Y270747D01*
X190344Y270775D01*
X190330Y270789D01*
X190217Y270902D01*
X190104Y271029D01*
X190020Y271170D01*
X189935Y271311D01*
X189879Y271438D01*
X189837Y271536D01*
X189808Y271607D01*
X189794Y271635D01*
X189724Y271861D01*
X189667Y272100D01*
X189625Y272340D01*
X189597Y272580D01*
X189583Y272791D01*
X189569Y272946D01*
Y273101D01*
X189583Y273440D01*
X189611Y273736D01*
X189653Y274018D01*
X189696Y274243D01*
X189738Y274440D01*
X189780Y274581D01*
X189794Y274638D01*
X189808Y274680D01*
X189822Y274694D01*
Y274708D01*
X189921Y274948D01*
X190048Y275159D01*
X190161Y275343D01*
X190273Y275498D01*
X190386Y275610D01*
X190471Y275695D01*
X190527Y275751D01*
X190541Y275765D01*
X190725Y275892D01*
X190922Y276005D01*
X191119Y276090D01*
X191303Y276160D01*
X191486Y276217D01*
X191613Y276259D01*
X191669Y276273D01*
X191711D01*
X191726Y276287D01*
X191740D01*
X191895Y275117D01*
X191641Y275032D01*
X191415Y274948D01*
X191232Y274849D01*
X191091Y274765D01*
X190978Y274680D01*
X190908Y274610D01*
X190866Y274553D01*
X190851Y274539D01*
X190753Y274370D01*
X190682Y274172D01*
X190626Y273961D01*
X190598Y273764D01*
X190570Y273566D01*
X190555Y273425D01*
Y273284D01*
X190570Y272960D01*
X190612Y272678D01*
X190682Y272453D01*
X190753Y272255D01*
X190837Y272114D01*
X190894Y272002D01*
X190950Y271931D01*
X190964Y271917D01*
X191091Y271804D01*
X191246Y271720D01*
X191415Y271649D01*
X191585Y271607D01*
X191740Y271579D01*
X191881Y271565D01*
X191965D01*
X191979D01*
X191993D01*
X192022D01*
X192078D01*
X192177D01*
X192261Y271579D01*
X192289D01*
X192304D01*
X192346Y271720D01*
X192388Y271875D01*
X192473Y272199D01*
X192543Y272565D01*
X192614Y272904D01*
X192642Y273073D01*
X192656Y273228D01*
X192684Y273369D01*
X192698Y273482D01*
X192712Y273580D01*
Y273651D01*
X192726Y273707D01*
Y273721D01*
X192755Y273975D01*
X192797Y274187D01*
X192825Y274370D01*
X192853Y274511D01*
X192867Y274624D01*
X192896Y274708D01*
X192910Y274765D01*
Y274779D01*
X192966Y274962D01*
X193022Y275117D01*
X193093Y275272D01*
X193149Y275399D01*
X193206Y275512D01*
X193262Y275582D01*
X193290Y275639D01*
X193304Y275653D01*
X193403Y275794D01*
X193516Y275907D01*
X193629Y276019D01*
X193741Y276104D01*
X193840Y276174D01*
X193925Y276231D01*
X193981Y276259D01*
X193995Y276273D01*
X194150Y276343D01*
X194319Y276400D01*
X194474Y276442D01*
X194629Y276470D01*
X194756Y276484D01*
X194855Y276499D01*
X194911D01*
X194940D01*
X195109Y276484D01*
D02*
G37*
G36*
X208831Y272213D02*
X204982D01*
X204743D01*
X204503Y272185D01*
X204306Y272157D01*
X204122Y272129D01*
X203953Y272086D01*
X203798Y272044D01*
X203657Y271987D01*
X203544Y271931D01*
X203446Y271889D01*
X203361Y271832D01*
X203291Y271790D01*
X203234Y271748D01*
X203164Y271691D01*
X203136Y271663D01*
X202966Y271452D01*
X202854Y271226D01*
X202769Y271001D01*
X202699Y270803D01*
X202670Y270620D01*
X202656Y270479D01*
X202642Y270423D01*
Y270352D01*
X202656Y270183D01*
X202670Y270014D01*
X202713Y269873D01*
X202755Y269760D01*
X202797Y269662D01*
X202826Y269577D01*
X202854Y269535D01*
X202868Y269520D01*
X202952Y269394D01*
X203051Y269281D01*
X203150Y269196D01*
X203234Y269126D01*
X203319Y269083D01*
X203389Y269041D01*
X203432Y269013D01*
X203446D01*
X203601Y268971D01*
X203770Y268928D01*
X203953Y268900D01*
X204137Y268886D01*
X204292Y268872D01*
X204419D01*
X204517D01*
X204531D01*
X204545D01*
X208831D01*
Y267674D01*
X204489D01*
X204193D01*
X203953Y267688D01*
X203756Y267702D01*
X203587D01*
X203474Y267716D01*
X203389Y267730D01*
X203333Y267744D01*
X203319D01*
X203136Y267787D01*
X202966Y267857D01*
X202826Y267913D01*
X202684Y267970D01*
X202586Y268040D01*
X202515Y268083D01*
X202459Y268111D01*
X202445Y268125D01*
X202304Y268238D01*
X202191Y268365D01*
X202078Y268491D01*
X201994Y268632D01*
X201923Y268745D01*
X201881Y268844D01*
X201853Y268900D01*
X201839Y268928D01*
X201754Y269126D01*
X201698Y269337D01*
X201656Y269535D01*
X201627Y269718D01*
X201613Y269873D01*
X201599Y269986D01*
Y270098D01*
X201613Y270366D01*
X201656Y270620D01*
X201712Y270846D01*
X201782Y271071D01*
X201867Y271269D01*
X201966Y271452D01*
X202078Y271621D01*
X202177Y271762D01*
X202290Y271903D01*
X202403Y272016D01*
X202501Y272114D01*
X202586Y272199D01*
X202656Y272255D01*
X202713Y272298D01*
X202755Y272326D01*
X202769Y272340D01*
X201754D01*
Y273411D01*
X208831D01*
Y272213D01*
D02*
G37*
G36*
X196800Y267307D02*
X192952D01*
X192712D01*
X192473Y267279D01*
X192275Y267251D01*
X192092Y267223D01*
X191923Y267180D01*
X191768Y267138D01*
X191627Y267082D01*
X191514Y267025D01*
X191415Y266983D01*
X191331Y266927D01*
X191260Y266884D01*
X191204Y266842D01*
X191133Y266786D01*
X191105Y266758D01*
X190936Y266546D01*
X190823Y266320D01*
X190739Y266095D01*
X190668Y265898D01*
X190640Y265714D01*
X190626Y265573D01*
X190612Y265517D01*
Y265446D01*
X190626Y265277D01*
X190640Y265108D01*
X190682Y264967D01*
X190725Y264854D01*
X190767Y264756D01*
X190795Y264671D01*
X190823Y264629D01*
X190837Y264615D01*
X190922Y264488D01*
X191021Y264375D01*
X191119Y264291D01*
X191204Y264220D01*
X191289Y264178D01*
X191359Y264135D01*
X191401Y264107D01*
X191415D01*
X191570Y264065D01*
X191740Y264023D01*
X191923Y263995D01*
X192106Y263980D01*
X192261Y263966D01*
X192388D01*
X192487D01*
X192501D01*
X192515D01*
X196800D01*
Y262768D01*
X192459D01*
X192162D01*
X191923Y262782D01*
X191726Y262796D01*
X191556D01*
X191444Y262810D01*
X191359Y262824D01*
X191303Y262838D01*
X191289D01*
X191105Y262881D01*
X190936Y262951D01*
X190795Y263008D01*
X190654Y263064D01*
X190555Y263135D01*
X190485Y263177D01*
X190429Y263205D01*
X190415Y263219D01*
X190273Y263332D01*
X190161Y263459D01*
X190048Y263586D01*
X189963Y263727D01*
X189893Y263839D01*
X189851Y263938D01*
X189822Y263995D01*
X189808Y264023D01*
X189724Y264220D01*
X189667Y264431D01*
X189625Y264629D01*
X189597Y264812D01*
X189583Y264967D01*
X189569Y265080D01*
Y265193D01*
X189583Y265461D01*
X189625Y265714D01*
X189681Y265940D01*
X189752Y266165D01*
X189837Y266363D01*
X189935Y266546D01*
X190048Y266715D01*
X190147Y266856D01*
X190259Y266997D01*
X190372Y267110D01*
X190471Y267209D01*
X190555Y267293D01*
X190626Y267350D01*
X190682Y267392D01*
X190725Y267420D01*
X190739Y267434D01*
X189724D01*
Y268505D01*
X196800D01*
Y267307D01*
D02*
G37*
G36*
X206054Y262289D02*
X206392Y262232D01*
X206688Y262148D01*
X206956Y262049D01*
X207167Y261950D01*
X207252Y261908D01*
X207322Y261880D01*
X207379Y261838D01*
X207421Y261824D01*
X207449Y261795D01*
X207463D01*
X207731Y261584D01*
X207971Y261358D01*
X208168Y261119D01*
X208337Y260893D01*
X208464Y260696D01*
X208549Y260527D01*
X208577Y260470D01*
X208605Y260428D01*
X208619Y260400D01*
Y260386D01*
X208746Y260033D01*
X208845Y259667D01*
X208901Y259300D01*
X208958Y258948D01*
X208972Y258779D01*
X208986Y258638D01*
Y258511D01*
X209000Y258398D01*
Y258172D01*
X208986Y257792D01*
X208944Y257439D01*
X208873Y257115D01*
X208803Y256847D01*
X208746Y256622D01*
X208704Y256523D01*
X208676Y256439D01*
X208648Y256382D01*
X208633Y256340D01*
X208619Y256312D01*
Y256297D01*
X208464Y256001D01*
X208295Y255748D01*
X208112Y255522D01*
X207943Y255339D01*
X207802Y255198D01*
X207675Y255099D01*
X207590Y255029D01*
X207576Y255015D01*
X207562D01*
X207294Y254860D01*
X207041Y254747D01*
X206801Y254676D01*
X206575Y254620D01*
X206378Y254592D01*
X206223Y254564D01*
X206166D01*
X206124D01*
X206110D01*
X206096D01*
X205814Y254578D01*
X205546Y254620D01*
X205307Y254690D01*
X205109Y254761D01*
X204940Y254846D01*
X204813Y254902D01*
X204743Y254958D01*
X204715Y254972D01*
X204503Y255142D01*
X204306Y255339D01*
X204137Y255550D01*
X203981Y255762D01*
X203869Y255945D01*
X203784Y256100D01*
X203756Y256157D01*
X203728Y256199D01*
X203714Y256227D01*
Y256241D01*
X203657Y256354D01*
X203615Y256495D01*
X203559Y256650D01*
X203502Y256819D01*
X203403Y257171D01*
X203305Y257538D01*
X203263Y257707D01*
X203220Y257862D01*
X203178Y258017D01*
X203150Y258144D01*
X203121Y258243D01*
X203107Y258328D01*
X203093Y258384D01*
Y258398D01*
X203023Y258680D01*
X202966Y258934D01*
X202896Y259159D01*
X202840Y259357D01*
X202769Y259540D01*
X202713Y259695D01*
X202656Y259836D01*
X202614Y259963D01*
X202558Y260061D01*
X202515Y260146D01*
X202487Y260202D01*
X202445Y260259D01*
X202403Y260329D01*
X202388Y260343D01*
X202248Y260470D01*
X202107Y260555D01*
X201966Y260625D01*
X201825Y260668D01*
X201712Y260696D01*
X201613Y260710D01*
X201557D01*
X201529D01*
X201303Y260682D01*
X201106Y260625D01*
X200937Y260541D01*
X200781Y260442D01*
X200669Y260357D01*
X200570Y260273D01*
X200514Y260217D01*
X200499Y260188D01*
X200429Y260075D01*
X200359Y259963D01*
X200246Y259695D01*
X200175Y259413D01*
X200119Y259131D01*
X200091Y258877D01*
X200077Y258764D01*
X200063Y258680D01*
Y258483D01*
X200077Y258088D01*
X200133Y257735D01*
X200218Y257453D01*
X200302Y257214D01*
X200387Y257031D01*
X200471Y256890D01*
X200528Y256819D01*
X200542Y256791D01*
X200739Y256594D01*
X200951Y256439D01*
X201176Y256312D01*
X201402Y256227D01*
X201613Y256171D01*
X201768Y256128D01*
X201839Y256114D01*
X201881Y256100D01*
X201909D01*
X201923D01*
X201825Y254860D01*
X201514Y254888D01*
X201232Y254958D01*
X200965Y255029D01*
X200739Y255128D01*
X200556Y255212D01*
X200415Y255282D01*
X200373Y255311D01*
X200330Y255339D01*
X200316Y255353D01*
X200302D01*
X200063Y255536D01*
X199851Y255734D01*
X199668Y255945D01*
X199527Y256157D01*
X199400Y256340D01*
X199329Y256481D01*
X199301Y256537D01*
X199273Y256579D01*
X199259Y256608D01*
Y256622D01*
X199146Y256932D01*
X199062Y257270D01*
X198991Y257580D01*
X198949Y257876D01*
X198921Y258144D01*
Y258243D01*
X198906Y258342D01*
Y258525D01*
X198921Y258891D01*
X198963Y259216D01*
X199019Y259526D01*
X199076Y259794D01*
X199132Y260005D01*
X199160Y260104D01*
X199188Y260174D01*
X199217Y260231D01*
X199231Y260273D01*
X199245Y260301D01*
Y260315D01*
X199386Y260597D01*
X199541Y260851D01*
X199710Y261062D01*
X199865Y261231D01*
X200006Y261358D01*
X200119Y261457D01*
X200203Y261528D01*
X200218Y261542D01*
X200232D01*
X200471Y261683D01*
X200711Y261781D01*
X200951Y261852D01*
X201162Y261894D01*
X201345Y261922D01*
X201486Y261950D01*
X201543D01*
X201585D01*
X201599D01*
X201613D01*
X201853Y261936D01*
X202078Y261894D01*
X202290Y261838D01*
X202473Y261781D01*
X202614Y261725D01*
X202727Y261668D01*
X202797Y261626D01*
X202826Y261612D01*
X203023Y261471D01*
X203206Y261302D01*
X203361Y261133D01*
X203488Y260964D01*
X203601Y260823D01*
X203671Y260696D01*
X203728Y260611D01*
X203742Y260597D01*
Y260583D01*
X203798Y260470D01*
X203855Y260343D01*
X203953Y260061D01*
X204052Y259737D01*
X204151Y259427D01*
X204235Y259145D01*
X204263Y259018D01*
X204292Y258906D01*
X204320Y258821D01*
X204334Y258750D01*
X204348Y258708D01*
Y258694D01*
X204404Y258454D01*
X204461Y258229D01*
X204517Y258032D01*
X204559Y257862D01*
X204602Y257693D01*
X204644Y257552D01*
X204672Y257425D01*
X204715Y257327D01*
X204743Y257228D01*
X204757Y257157D01*
X204799Y257045D01*
X204813Y256974D01*
X204827Y256960D01*
X204912Y256749D01*
X205011Y256565D01*
X205109Y256410D01*
X205194Y256297D01*
X205278Y256199D01*
X205335Y256143D01*
X205377Y256100D01*
X205391Y256086D01*
X205518Y255987D01*
X205659Y255917D01*
X205800Y255875D01*
X205913Y255832D01*
X206026Y255818D01*
X206110Y255804D01*
X206181D01*
X206195D01*
X206364Y255818D01*
X206519Y255846D01*
X206660Y255889D01*
X206773Y255945D01*
X206885Y256001D01*
X206956Y256044D01*
X207012Y256072D01*
X207026Y256086D01*
X207167Y256199D01*
X207280Y256340D01*
X207379Y256481D01*
X207477Y256608D01*
X207534Y256735D01*
X207590Y256833D01*
X207619Y256904D01*
X207633Y256932D01*
X207703Y257143D01*
X207759Y257369D01*
X207788Y257595D01*
X207816Y257792D01*
X207830Y257961D01*
X207844Y258102D01*
Y258229D01*
X207830Y258539D01*
X207802Y258821D01*
X207759Y259075D01*
X207703Y259300D01*
X207647Y259484D01*
X207604Y259624D01*
X207590Y259667D01*
X207576Y259709D01*
X207562Y259723D01*
Y259737D01*
X207449Y259963D01*
X207322Y260174D01*
X207196Y260329D01*
X207069Y260470D01*
X206970Y260583D01*
X206871Y260653D01*
X206815Y260696D01*
X206801Y260710D01*
X206618Y260809D01*
X206420Y260907D01*
X206209Y260964D01*
X206026Y261020D01*
X205842Y261062D01*
X205715Y261091D01*
X205659D01*
X205617Y261105D01*
X205603D01*
X205588D01*
X205701Y262317D01*
X206054Y262289D01*
D02*
G37*
G36*
X193671Y261358D02*
X194037Y261316D01*
X194362Y261246D01*
X194644Y261175D01*
X194771Y261147D01*
X194869Y261119D01*
X194968Y261076D01*
X195052Y261048D01*
X195109Y261020D01*
X195151Y261006D01*
X195179Y260992D01*
X195193D01*
X195489Y260837D01*
X195743Y260653D01*
X195969Y260470D01*
X196152Y260287D01*
X196293Y260132D01*
X196406Y260005D01*
X196462Y259921D01*
X196490Y259906D01*
Y259892D01*
X196645Y259624D01*
X196758Y259357D01*
X196843Y259089D01*
X196899Y258849D01*
X196927Y258652D01*
X196941Y258483D01*
X196956Y258426D01*
Y258342D01*
X196941Y258102D01*
X196913Y257876D01*
X196857Y257665D01*
X196786Y257482D01*
X196716Y257298D01*
X196631Y257129D01*
X196533Y256988D01*
X196434Y256861D01*
X196335Y256735D01*
X196237Y256636D01*
X196152Y256551D01*
X196082Y256481D01*
X196011Y256424D01*
X195955Y256382D01*
X195926Y256368D01*
X195912Y256354D01*
X196800D01*
Y255240D01*
X187045D01*
Y256439D01*
X190541D01*
X190386Y256565D01*
X190259Y256706D01*
X190133Y256833D01*
X190034Y256974D01*
X189963Y257087D01*
X189893Y257171D01*
X189865Y257228D01*
X189851Y257256D01*
X189752Y257439D01*
X189681Y257637D01*
X189639Y257834D01*
X189597Y258017D01*
X189583Y258172D01*
X189569Y258285D01*
Y258398D01*
X189583Y258708D01*
X189639Y259004D01*
X189710Y259272D01*
X189794Y259498D01*
X189893Y259695D01*
X189963Y259836D01*
X189992Y259892D01*
X190020Y259935D01*
X190034Y259949D01*
Y259963D01*
X190217Y260217D01*
X190443Y260428D01*
X190654Y260611D01*
X190866Y260752D01*
X191063Y260865D01*
X191218Y260949D01*
X191274Y260978D01*
X191317Y261006D01*
X191345Y261020D01*
X191359D01*
X191683Y261133D01*
X192022Y261217D01*
X192346Y261288D01*
X192642Y261330D01*
X192896Y261358D01*
X193008D01*
X193093Y261373D01*
X193178D01*
X193234D01*
X193262D01*
X193276D01*
X193671Y261358D01*
D02*
G37*
G36*
X202684Y252745D02*
X206773D01*
X206970D01*
X207139D01*
X207294Y252731D01*
X207449Y252717D01*
X207576D01*
X207689Y252703D01*
X207872Y252675D01*
X208013Y252646D01*
X208112Y252632D01*
X208168Y252604D01*
X208182D01*
X208309Y252548D01*
X208408Y252463D01*
X208507Y252379D01*
X208577Y252308D01*
X208648Y252223D01*
X208690Y252167D01*
X208718Y252125D01*
X208732Y252111D01*
X208803Y251956D01*
X208845Y251801D01*
X208887Y251631D01*
X208901Y251462D01*
X208915Y251321D01*
X208930Y251208D01*
Y251096D01*
X208915Y250786D01*
X208901Y250630D01*
X208873Y250490D01*
X208859Y250363D01*
X208845Y250264D01*
X208831Y250208D01*
Y250179D01*
X207773Y250334D01*
X207788Y250447D01*
X207802Y250560D01*
Y250659D01*
X207816Y250729D01*
Y250870D01*
X207802Y251053D01*
X207773Y251180D01*
X207745Y251251D01*
X207731Y251279D01*
X207661Y251378D01*
X207590Y251434D01*
X207534Y251476D01*
X207506Y251490D01*
X207435Y251505D01*
X207337Y251519D01*
X207111Y251533D01*
X207012Y251547D01*
X206928D01*
X206871D01*
X206843D01*
X202684D01*
Y250334D01*
X201754D01*
Y251547D01*
X199287D01*
X200006Y252745D01*
X201754D01*
Y253633D01*
X202684D01*
Y252745D01*
D02*
G37*
G36*
X208831Y247445D02*
X207463D01*
Y248812D01*
X208831D01*
Y247445D01*
D02*
G37*
G36*
X193586Y253774D02*
X193897Y253746D01*
X194178Y253704D01*
X194446Y253647D01*
X194686Y253577D01*
X194911Y253506D01*
X195123Y253422D01*
X195306Y253337D01*
X195475Y253253D01*
X195616Y253168D01*
X195729Y253097D01*
X195828Y253027D01*
X195912Y252971D01*
X195969Y252928D01*
X195997Y252900D01*
X196011Y252886D01*
X196180Y252703D01*
X196321Y252519D01*
X196448Y252322D01*
X196561Y252125D01*
X196645Y251928D01*
X196730Y251716D01*
X196843Y251335D01*
X196871Y251166D01*
X196899Y250997D01*
X196927Y250856D01*
X196941Y250729D01*
X196956Y250616D01*
Y250476D01*
X196941Y250137D01*
X196885Y249827D01*
X196814Y249531D01*
X196744Y249291D01*
X196660Y249080D01*
X196631Y248995D01*
X196603Y248925D01*
X196575Y248854D01*
X196547Y248812D01*
X196533Y248798D01*
Y248784D01*
X196349Y248502D01*
X196152Y248262D01*
X195955Y248051D01*
X195757Y247882D01*
X195588Y247755D01*
X195447Y247656D01*
X195391Y247628D01*
X195348Y247600D01*
X195334Y247586D01*
X195320D01*
X194996Y247445D01*
X194644Y247346D01*
X194291Y247261D01*
X193939Y247219D01*
X193784Y247191D01*
X193643D01*
X193502Y247177D01*
X193389Y247163D01*
X193290D01*
X193220D01*
X193178D01*
X193163D01*
X192853Y247177D01*
X192571Y247205D01*
X192304Y247247D01*
X192050Y247304D01*
X191810Y247374D01*
X191599Y247459D01*
X191387Y247543D01*
X191218Y247628D01*
X191063Y247712D01*
X190922Y247797D01*
X190795Y247882D01*
X190696Y247952D01*
X190626Y248008D01*
X190570Y248051D01*
X190541Y248079D01*
X190527Y248093D01*
X190358Y248276D01*
X190217Y248460D01*
X190076Y248657D01*
X189977Y248854D01*
X189879Y249052D01*
X189808Y249249D01*
X189681Y249630D01*
X189653Y249813D01*
X189625Y249968D01*
X189597Y250109D01*
X189583Y250236D01*
X189569Y250334D01*
Y250476D01*
X189583Y250715D01*
X189597Y250941D01*
X189696Y251378D01*
X189822Y251758D01*
X189893Y251928D01*
X189963Y252083D01*
X190034Y252223D01*
X190104Y252336D01*
X190175Y252449D01*
X190231Y252534D01*
X190288Y252604D01*
X190330Y252661D01*
X190344Y252689D01*
X190358Y252703D01*
X190541Y252900D01*
X190753Y253055D01*
X190978Y253210D01*
X191204Y253323D01*
X191444Y253436D01*
X191697Y253520D01*
X191937Y253591D01*
X192162Y253647D01*
X192388Y253704D01*
X192585Y253732D01*
X192783Y253760D01*
X192938Y253774D01*
X193079D01*
X193178Y253788D01*
X193234D01*
X193262D01*
X193586Y253774D01*
D02*
G37*
G36*
X206589Y242060D02*
X206829Y242017D01*
X207041Y241989D01*
X207238Y241933D01*
X207407Y241876D01*
X207576Y241820D01*
X207717Y241763D01*
X207844Y241693D01*
X207957Y241637D01*
X208055Y241580D01*
X208126Y241524D01*
X208182Y241482D01*
X208239Y241453D01*
X208253Y241439D01*
X208267Y241425D01*
X208394Y241284D01*
X208507Y241143D01*
X208605Y240988D01*
X208690Y240819D01*
X208817Y240495D01*
X208901Y240185D01*
X208958Y239889D01*
X208972Y239776D01*
X208986Y239663D01*
X209000Y239578D01*
Y239452D01*
X208986Y239142D01*
X208944Y238860D01*
X208887Y238606D01*
X208817Y238380D01*
X208760Y238197D01*
X208704Y238070D01*
X208662Y237985D01*
X208648Y237957D01*
X208507Y237732D01*
X208337Y237534D01*
X208168Y237379D01*
X208013Y237238D01*
X207858Y237140D01*
X207745Y237069D01*
X207661Y237027D01*
X207647Y237013D01*
X207633D01*
X207351Y236914D01*
X207055Y236830D01*
X206730Y236773D01*
X206420Y236745D01*
X206152Y236717D01*
X206040D01*
X205927Y236703D01*
X205842D01*
X205786D01*
X205744D01*
X205730D01*
X199076D01*
Y238000D01*
X205800D01*
X206096D01*
X206350Y238028D01*
X206561Y238042D01*
X206730Y238070D01*
X206857Y238098D01*
X206956Y238112D01*
X207012Y238141D01*
X207026D01*
X207167Y238197D01*
X207280Y238267D01*
X207379Y238352D01*
X207477Y238423D01*
X207534Y238507D01*
X207590Y238563D01*
X207619Y238606D01*
X207633Y238620D01*
X207703Y238761D01*
X207759Y238902D01*
X207788Y239043D01*
X207816Y239170D01*
X207830Y239296D01*
X207844Y239381D01*
Y239466D01*
X207830Y239691D01*
X207773Y239903D01*
X207717Y240072D01*
X207633Y240227D01*
X207562Y240340D01*
X207492Y240424D01*
X207449Y240481D01*
X207435Y240495D01*
X207351Y240565D01*
X207252Y240622D01*
X207026Y240706D01*
X206773Y240791D01*
X206519Y240833D01*
X206279Y240875D01*
X206181D01*
X206096Y240889D01*
X206011Y240904D01*
X205955D01*
X205927D01*
X205913D01*
X206082Y242074D01*
X206350D01*
X206589Y242060D01*
D02*
G37*
G36*
X196800Y240509D02*
X192839D01*
Y238014D01*
X192825Y237647D01*
X192797Y237295D01*
X192755Y236985D01*
X192698Y236703D01*
X192642Y236435D01*
X192571Y236209D01*
X192487Y235998D01*
X192402Y235815D01*
X192332Y235660D01*
X192247Y235519D01*
X192177Y235406D01*
X192106Y235321D01*
X192064Y235251D01*
X192022Y235208D01*
X191993Y235180D01*
X191979Y235166D01*
X191810Y235025D01*
X191641Y234898D01*
X191472Y234800D01*
X191289Y234701D01*
X191105Y234616D01*
X190936Y234560D01*
X190612Y234461D01*
X190457Y234433D01*
X190316Y234405D01*
X190189Y234391D01*
X190090Y234377D01*
X189992Y234363D01*
X189935D01*
X189893D01*
X189879D01*
X189611Y234377D01*
X189357Y234405D01*
X189132Y234461D01*
X188934Y234504D01*
X188765Y234560D01*
X188638Y234616D01*
X188568Y234645D01*
X188540Y234659D01*
X188328Y234771D01*
X188145Y234912D01*
X187976Y235039D01*
X187849Y235166D01*
X187750Y235279D01*
X187666Y235364D01*
X187623Y235420D01*
X187609Y235448D01*
X187496Y235631D01*
X187398Y235843D01*
X187313Y236040D01*
X187243Y236223D01*
X187200Y236393D01*
X187172Y236519D01*
X187144Y236618D01*
Y236646D01*
X187116Y236858D01*
X187088Y237097D01*
X187073Y237351D01*
X187059Y237591D01*
X187045Y237802D01*
Y241806D01*
X196800D01*
Y240509D01*
D02*
G37*
G36*
Y231670D02*
X189724D01*
Y232868D01*
X196800D01*
Y231670D01*
D02*
G37*
G36*
X188413D02*
X187045D01*
Y232868D01*
X188413D01*
Y231670D01*
D02*
G37*
G36*
X207139Y235138D02*
X207280Y235124D01*
X207576Y235053D01*
X207816Y234955D01*
X208027Y234842D01*
X208197Y234729D01*
X208323Y234630D01*
X208394Y234560D01*
X208422Y234532D01*
X208605Y234278D01*
X208746Y233996D01*
X208845Y233686D01*
X208915Y233404D01*
X208958Y233150D01*
X208972Y233037D01*
Y232939D01*
X208986Y232854D01*
Y232741D01*
X208972Y232488D01*
X208944Y232234D01*
X208915Y232008D01*
X208873Y231811D01*
X208831Y231656D01*
X208789Y231529D01*
X208774Y231444D01*
X208760Y231416D01*
X208662Y231177D01*
X208535Y230951D01*
X208394Y230740D01*
X208267Y230528D01*
X208140Y230359D01*
X208041Y230232D01*
X207971Y230148D01*
X207943Y230133D01*
Y230119D01*
X208126Y230091D01*
X208295Y230063D01*
X208450Y230035D01*
X208577Y229993D01*
X208690Y229950D01*
X208760Y229922D01*
X208817Y229908D01*
X208831Y229894D01*
Y228639D01*
X208676Y228710D01*
X208521Y228780D01*
X208380Y228837D01*
X208253Y228865D01*
X208140Y228907D01*
X208055Y228921D01*
X207999Y228935D01*
X207985D01*
X207886Y228949D01*
X207759Y228963D01*
X207619D01*
X207463Y228978D01*
X207111Y228992D01*
X206759D01*
X206420Y229006D01*
X206265D01*
X206138D01*
X206026D01*
X205941D01*
X205885D01*
X205870D01*
X204263D01*
X203996D01*
X203756Y229020D01*
X203573Y229034D01*
X203418D01*
X203305Y229048D01*
X203220Y229062D01*
X203178Y229076D01*
X203164D01*
X202981Y229118D01*
X202826Y229175D01*
X202699Y229231D01*
X202572Y229302D01*
X202487Y229358D01*
X202417Y229401D01*
X202374Y229429D01*
X202360Y229443D01*
X202248Y229555D01*
X202135Y229682D01*
X202050Y229823D01*
X201966Y229964D01*
X201909Y230091D01*
X201867Y230190D01*
X201839Y230260D01*
X201825Y230289D01*
X201754Y230514D01*
X201698Y230754D01*
X201656Y230993D01*
X201627Y231233D01*
X201613Y231444D01*
X201599Y231600D01*
Y231755D01*
X201613Y232093D01*
X201641Y232389D01*
X201684Y232671D01*
X201726Y232896D01*
X201768Y233094D01*
X201810Y233235D01*
X201825Y233291D01*
X201839Y233333D01*
X201853Y233348D01*
Y233362D01*
X201952Y233601D01*
X202078Y233813D01*
X202191Y233996D01*
X202304Y234151D01*
X202417Y234264D01*
X202501Y234349D01*
X202558Y234405D01*
X202572Y234419D01*
X202755Y234546D01*
X202952Y234659D01*
X203150Y234743D01*
X203333Y234814D01*
X203516Y234870D01*
X203643Y234912D01*
X203699Y234926D01*
X203742D01*
X203756Y234941D01*
X203770D01*
X203925Y233771D01*
X203671Y233686D01*
X203446Y233601D01*
X203263Y233503D01*
X203121Y233418D01*
X203009Y233333D01*
X202938Y233263D01*
X202896Y233207D01*
X202882Y233193D01*
X202783Y233023D01*
X202713Y232826D01*
X202656Y232615D01*
X202628Y232417D01*
X202600Y232220D01*
X202586Y232079D01*
Y231938D01*
X202600Y231614D01*
X202642Y231332D01*
X202713Y231106D01*
X202783Y230909D01*
X202868Y230768D01*
X202924Y230655D01*
X202981Y230585D01*
X202995Y230571D01*
X203121Y230458D01*
X203277Y230373D01*
X203446Y230303D01*
X203615Y230260D01*
X203770Y230232D01*
X203911Y230218D01*
X203996D01*
X204010D01*
X204024D01*
X204052D01*
X204108D01*
X204207D01*
X204292Y230232D01*
X204320D01*
X204334D01*
X204376Y230373D01*
X204419Y230528D01*
X204503Y230852D01*
X204573Y231219D01*
X204644Y231557D01*
X204672Y231726D01*
X204686Y231882D01*
X204715Y232022D01*
X204729Y232135D01*
X204743Y232234D01*
Y232304D01*
X204757Y232361D01*
Y232375D01*
X204785Y232629D01*
X204827Y232840D01*
X204855Y233023D01*
X204884Y233164D01*
X204898Y233277D01*
X204926Y233362D01*
X204940Y233418D01*
Y233432D01*
X204996Y233615D01*
X205053Y233771D01*
X205123Y233926D01*
X205180Y234053D01*
X205236Y234165D01*
X205292Y234236D01*
X205321Y234292D01*
X205335Y234306D01*
X205433Y234447D01*
X205546Y234560D01*
X205659Y234673D01*
X205772Y234757D01*
X205870Y234828D01*
X205955Y234884D01*
X206011Y234912D01*
X206026Y234926D01*
X206181Y234997D01*
X206350Y235053D01*
X206505Y235096D01*
X206660Y235124D01*
X206787Y235138D01*
X206885Y235152D01*
X206942D01*
X206970D01*
X207139Y235138D01*
D02*
G37*
G36*
X196800Y228639D02*
X192952D01*
X192712D01*
X192473Y228611D01*
X192275Y228583D01*
X192092Y228555D01*
X191923Y228512D01*
X191768Y228470D01*
X191627Y228414D01*
X191514Y228357D01*
X191415Y228315D01*
X191331Y228259D01*
X191260Y228216D01*
X191204Y228174D01*
X191133Y228118D01*
X191105Y228089D01*
X190936Y227878D01*
X190823Y227652D01*
X190739Y227427D01*
X190668Y227229D01*
X190640Y227046D01*
X190626Y226905D01*
X190612Y226849D01*
Y226778D01*
X190626Y226609D01*
X190640Y226440D01*
X190682Y226299D01*
X190725Y226186D01*
X190767Y226088D01*
X190795Y226003D01*
X190823Y225961D01*
X190837Y225947D01*
X190922Y225820D01*
X191021Y225707D01*
X191119Y225623D01*
X191204Y225552D01*
X191289Y225510D01*
X191359Y225467D01*
X191401Y225439D01*
X191415D01*
X191570Y225397D01*
X191740Y225355D01*
X191923Y225326D01*
X192106Y225312D01*
X192261Y225298D01*
X192388D01*
X192487D01*
X192501D01*
X192515D01*
X196800D01*
Y224100D01*
X192459D01*
X192162D01*
X191923Y224114D01*
X191726Y224128D01*
X191556D01*
X191444Y224142D01*
X191359Y224156D01*
X191303Y224170D01*
X191289D01*
X191105Y224213D01*
X190936Y224283D01*
X190795Y224340D01*
X190654Y224396D01*
X190555Y224466D01*
X190485Y224509D01*
X190429Y224537D01*
X190415Y224551D01*
X190273Y224664D01*
X190161Y224791D01*
X190048Y224918D01*
X189963Y225059D01*
X189893Y225171D01*
X189851Y225270D01*
X189822Y225326D01*
X189808Y225355D01*
X189724Y225552D01*
X189667Y225763D01*
X189625Y225961D01*
X189597Y226144D01*
X189583Y226299D01*
X189569Y226412D01*
Y226525D01*
X189583Y226793D01*
X189625Y227046D01*
X189681Y227272D01*
X189752Y227497D01*
X189837Y227695D01*
X189935Y227878D01*
X190048Y228047D01*
X190147Y228188D01*
X190259Y228329D01*
X190372Y228442D01*
X190471Y228540D01*
X190555Y228625D01*
X190626Y228682D01*
X190682Y228724D01*
X190725Y228752D01*
X190739Y228766D01*
X189724D01*
Y229837D01*
X196800D01*
Y228639D01*
D02*
G37*
G36*
X195109Y222648D02*
X195250Y222634D01*
X195546Y222563D01*
X195786Y222465D01*
X195997Y222352D01*
X196166Y222239D01*
X196293Y222141D01*
X196363Y222070D01*
X196392Y222042D01*
X196575Y221788D01*
X196716Y221506D01*
X196814Y221196D01*
X196885Y220914D01*
X196927Y220660D01*
X196941Y220548D01*
Y220449D01*
X196956Y220364D01*
Y220252D01*
X196941Y219998D01*
X196913Y219744D01*
X196885Y219519D01*
X196843Y219321D01*
X196800Y219166D01*
X196758Y219039D01*
X196744Y218955D01*
X196730Y218926D01*
X196631Y218687D01*
X196504Y218461D01*
X196363Y218250D01*
X196237Y218038D01*
X196110Y217869D01*
X196011Y217742D01*
X195940Y217658D01*
X195912Y217644D01*
Y217630D01*
X196096Y217601D01*
X196265Y217573D01*
X196420Y217545D01*
X196547Y217503D01*
X196660Y217460D01*
X196730Y217432D01*
X196786Y217418D01*
X196800Y217404D01*
Y216149D01*
X196645Y216220D01*
X196490Y216290D01*
X196349Y216347D01*
X196222Y216375D01*
X196110Y216417D01*
X196025Y216431D01*
X195969Y216445D01*
X195955D01*
X195856Y216459D01*
X195729Y216474D01*
X195588D01*
X195433Y216488D01*
X195081Y216502D01*
X194728D01*
X194390Y216516D01*
X194235D01*
X194108D01*
X193995D01*
X193911D01*
X193854D01*
X193840D01*
X192233D01*
X191965D01*
X191726Y216530D01*
X191542Y216544D01*
X191387D01*
X191274Y216558D01*
X191190Y216572D01*
X191147Y216586D01*
X191133D01*
X190950Y216629D01*
X190795Y216685D01*
X190668Y216741D01*
X190541Y216812D01*
X190457Y216868D01*
X190386Y216910D01*
X190344Y216939D01*
X190330Y216953D01*
X190217Y217066D01*
X190104Y217192D01*
X190020Y217333D01*
X189935Y217474D01*
X189879Y217601D01*
X189837Y217700D01*
X189808Y217770D01*
X189794Y217799D01*
X189724Y218024D01*
X189667Y218264D01*
X189625Y218503D01*
X189597Y218743D01*
X189583Y218955D01*
X189569Y219110D01*
Y219265D01*
X189583Y219603D01*
X189611Y219899D01*
X189653Y220181D01*
X189696Y220407D01*
X189738Y220604D01*
X189780Y220745D01*
X189794Y220801D01*
X189808Y220844D01*
X189822Y220858D01*
Y220872D01*
X189921Y221111D01*
X190048Y221323D01*
X190161Y221506D01*
X190273Y221661D01*
X190386Y221774D01*
X190471Y221859D01*
X190527Y221915D01*
X190541Y221929D01*
X190725Y222056D01*
X190922Y222169D01*
X191119Y222253D01*
X191303Y222324D01*
X191486Y222380D01*
X191613Y222422D01*
X191669Y222437D01*
X191711D01*
X191726Y222451D01*
X191740D01*
X191895Y221281D01*
X191641Y221196D01*
X191415Y221111D01*
X191232Y221013D01*
X191091Y220928D01*
X190978Y220844D01*
X190908Y220773D01*
X190866Y220717D01*
X190851Y220703D01*
X190753Y220533D01*
X190682Y220336D01*
X190626Y220125D01*
X190598Y219927D01*
X190570Y219730D01*
X190555Y219589D01*
Y219448D01*
X190570Y219124D01*
X190612Y218842D01*
X190682Y218616D01*
X190753Y218419D01*
X190837Y218278D01*
X190894Y218165D01*
X190950Y218095D01*
X190964Y218081D01*
X191091Y217968D01*
X191246Y217883D01*
X191415Y217813D01*
X191585Y217770D01*
X191740Y217742D01*
X191881Y217728D01*
X191965D01*
X191979D01*
X191993D01*
X192022D01*
X192078D01*
X192177D01*
X192261Y217742D01*
X192289D01*
X192304D01*
X192346Y217883D01*
X192388Y218038D01*
X192473Y218363D01*
X192543Y218729D01*
X192614Y219067D01*
X192642Y219237D01*
X192656Y219392D01*
X192684Y219533D01*
X192698Y219645D01*
X192712Y219744D01*
Y219814D01*
X192726Y219871D01*
Y219885D01*
X192755Y220139D01*
X192797Y220350D01*
X192825Y220533D01*
X192853Y220674D01*
X192867Y220787D01*
X192896Y220872D01*
X192910Y220928D01*
Y220942D01*
X192966Y221126D01*
X193022Y221281D01*
X193093Y221436D01*
X193149Y221562D01*
X193206Y221675D01*
X193262Y221746D01*
X193290Y221802D01*
X193304Y221816D01*
X193403Y221957D01*
X193516Y222070D01*
X193629Y222183D01*
X193741Y222267D01*
X193840Y222338D01*
X193925Y222394D01*
X193981Y222422D01*
X193995Y222437D01*
X194150Y222507D01*
X194319Y222563D01*
X194474Y222606D01*
X194629Y222634D01*
X194756Y222648D01*
X194855Y222662D01*
X194911D01*
X194940D01*
X195109Y222648D01*
D02*
G37*
G36*
X208831Y225975D02*
X205166D01*
X204827Y225961D01*
X204531Y225947D01*
X204277Y225919D01*
X204066Y225876D01*
X203911Y225834D01*
X203798Y225806D01*
X203728Y225792D01*
X203699Y225777D01*
X203516Y225693D01*
X203361Y225594D01*
X203220Y225496D01*
X203107Y225397D01*
X203023Y225298D01*
X202966Y225228D01*
X202924Y225171D01*
X202910Y225157D01*
X202826Y224988D01*
X202755Y224833D01*
X202713Y224664D01*
X202670Y224523D01*
X202656Y224410D01*
X202642Y224311D01*
Y224227D01*
X202656Y223987D01*
X202699Y223790D01*
X202769Y223621D01*
X202840Y223494D01*
X202924Y223395D01*
X202981Y223325D01*
X203037Y223282D01*
X203051Y223268D01*
X203220Y223170D01*
X203403Y223099D01*
X203601Y223043D01*
X203798Y223015D01*
X203967Y222986D01*
X204122Y222972D01*
X204179D01*
X204207D01*
X204235D01*
X204249D01*
X208831D01*
Y221774D01*
X204729D01*
X204348Y221746D01*
X204024Y221689D01*
X203756Y221619D01*
X203530Y221520D01*
X203361Y221436D01*
X203248Y221351D01*
X203178Y221295D01*
X203150Y221281D01*
X202981Y221083D01*
X202854Y220872D01*
X202769Y220660D01*
X202699Y220463D01*
X202670Y220294D01*
X202656Y220153D01*
X202642Y220096D01*
Y220026D01*
X202656Y219871D01*
X202670Y219744D01*
X202699Y219617D01*
X202741Y219519D01*
X202783Y219420D01*
X202811Y219363D01*
X202826Y219321D01*
X202840Y219307D01*
X202924Y219194D01*
X203009Y219110D01*
X203093Y219039D01*
X203178Y218983D01*
X203248Y218941D01*
X203305Y218912D01*
X203347Y218884D01*
X203361D01*
X203488Y218842D01*
X203657Y218814D01*
X203826Y218799D01*
X203996Y218785D01*
X204151Y218771D01*
X204277D01*
X204362D01*
X204376D01*
X204390D01*
X208831D01*
Y217573D01*
X203981D01*
X203756D01*
X203559Y217601D01*
X203361Y217630D01*
X203192Y217658D01*
X203023Y217700D01*
X202882Y217756D01*
X202755Y217799D01*
X202628Y217855D01*
X202530Y217911D01*
X202431Y217954D01*
X202304Y218052D01*
X202219Y218109D01*
X202191Y218137D01*
X201994Y218363D01*
X201853Y218630D01*
X201740Y218898D01*
X201670Y219152D01*
X201627Y219392D01*
X201613Y219490D01*
Y219589D01*
X201599Y219659D01*
Y219758D01*
X201613Y220012D01*
X201656Y220237D01*
X201712Y220463D01*
X201796Y220674D01*
X201895Y220872D01*
X201994Y221055D01*
X202107Y221210D01*
X202219Y221365D01*
X202346Y221506D01*
X202459Y221619D01*
X202558Y221718D01*
X202656Y221802D01*
X202741Y221873D01*
X202797Y221915D01*
X202840Y221943D01*
X202854Y221957D01*
X202642Y222042D01*
X202459Y222155D01*
X202304Y222281D01*
X202177Y222394D01*
X202064Y222507D01*
X201994Y222592D01*
X201952Y222648D01*
X201937Y222676D01*
X201825Y222873D01*
X201740Y223085D01*
X201684Y223297D01*
X201641Y223508D01*
X201613Y223677D01*
X201599Y223832D01*
Y223959D01*
X201613Y224213D01*
X201656Y224452D01*
X201698Y224664D01*
X201754Y224847D01*
X201825Y225002D01*
X201867Y225115D01*
X201909Y225186D01*
X201923Y225214D01*
X202050Y225411D01*
X202191Y225580D01*
X202332Y225735D01*
X202473Y225862D01*
X202586Y225961D01*
X202684Y226045D01*
X202741Y226088D01*
X202769Y226102D01*
X201754D01*
Y227173D01*
X208831D01*
Y225975D01*
D02*
G37*
G36*
X196800Y213499D02*
X187045D01*
Y214697D01*
X196800D01*
Y213499D01*
D02*
G37*
G36*
X205673Y216192D02*
X205969Y216163D01*
X206251Y216121D01*
X206505Y216065D01*
X206744Y215994D01*
X206970Y215924D01*
X207167Y215839D01*
X207351Y215755D01*
X207506Y215670D01*
X207647Y215585D01*
X207759Y215515D01*
X207858Y215444D01*
X207943Y215388D01*
X207999Y215346D01*
X208027Y215318D01*
X208041Y215303D01*
X208211Y215120D01*
X208351Y214937D01*
X208478Y214740D01*
X208591Y214528D01*
X208676Y214331D01*
X208760Y214119D01*
X208873Y213725D01*
X208901Y213541D01*
X208930Y213372D01*
X208958Y213217D01*
X208972Y213090D01*
X208986Y212992D01*
Y212836D01*
X208958Y212400D01*
X208887Y212005D01*
X208803Y211652D01*
X208746Y211511D01*
X208690Y211370D01*
X208633Y211243D01*
X208577Y211131D01*
X208535Y211046D01*
X208493Y210962D01*
X208450Y210905D01*
X208422Y210863D01*
X208394Y210835D01*
Y210821D01*
X208140Y210539D01*
X207872Y210313D01*
X207590Y210116D01*
X207322Y209975D01*
X207083Y209862D01*
X206970Y209820D01*
X206885Y209777D01*
X206801Y209749D01*
X206744Y209735D01*
X206716Y209721D01*
X206702D01*
X206547Y210962D01*
X206815Y211074D01*
X207041Y211201D01*
X207238Y211328D01*
X207393Y211441D01*
X207506Y211540D01*
X207590Y211624D01*
X207647Y211695D01*
X207661Y211709D01*
X207773Y211892D01*
X207858Y212075D01*
X207915Y212273D01*
X207957Y212442D01*
X207985Y212597D01*
X207999Y212724D01*
Y212836D01*
X207985Y213006D01*
X207971Y213161D01*
X207900Y213443D01*
X207802Y213696D01*
X207689Y213922D01*
X207590Y214091D01*
X207492Y214218D01*
X207421Y214303D01*
X207393Y214317D01*
Y214331D01*
X207139Y214528D01*
X206857Y214683D01*
X206547Y214796D01*
X206265Y214881D01*
X206011Y214923D01*
X205899Y214951D01*
X205800Y214965D01*
X205715D01*
X205659Y214979D01*
X205617D01*
X205603D01*
Y209693D01*
X205462Y209679D01*
X205363D01*
X205307D01*
X205292D01*
X204968Y209693D01*
X204672Y209721D01*
X204390Y209763D01*
X204122Y209820D01*
X203883Y209890D01*
X203657Y209961D01*
X203460Y210045D01*
X203277Y210130D01*
X203107Y210214D01*
X202966Y210299D01*
X202854Y210369D01*
X202755Y210440D01*
X202670Y210496D01*
X202614Y210539D01*
X202586Y210567D01*
X202572Y210581D01*
X202403Y210750D01*
X202248Y210933D01*
X202121Y211131D01*
X202008Y211328D01*
X201909Y211525D01*
X201839Y211709D01*
X201768Y211906D01*
X201726Y212075D01*
X201684Y212258D01*
X201656Y212414D01*
X201627Y212554D01*
X201613Y212667D01*
X201599Y212766D01*
Y212907D01*
X201613Y213175D01*
X201641Y213429D01*
X201684Y213668D01*
X201754Y213894D01*
X201825Y214105D01*
X201909Y214303D01*
X201994Y214486D01*
X202092Y214641D01*
X202177Y214796D01*
X202276Y214923D01*
X202360Y215036D01*
X202431Y215120D01*
X202501Y215191D01*
X202544Y215247D01*
X202572Y215275D01*
X202586Y215289D01*
X202783Y215444D01*
X202995Y215585D01*
X203206Y215712D01*
X203432Y215825D01*
X203671Y215910D01*
X203897Y215980D01*
X204348Y216093D01*
X204545Y216135D01*
X204743Y216163D01*
X204912Y216178D01*
X205067Y216192D01*
X205194Y216206D01*
X205278D01*
X205349D01*
X205363D01*
X205673Y216192D01*
D02*
G37*
G36*
X193643Y212033D02*
X193939Y212005D01*
X194221Y211963D01*
X194474Y211906D01*
X194714Y211836D01*
X194940Y211765D01*
X195137Y211681D01*
X195320Y211596D01*
X195475Y211511D01*
X195616Y211427D01*
X195729Y211356D01*
X195828Y211286D01*
X195912Y211229D01*
X195969Y211187D01*
X195997Y211159D01*
X196011Y211145D01*
X196180Y210962D01*
X196321Y210778D01*
X196448Y210581D01*
X196561Y210369D01*
X196645Y210172D01*
X196730Y209961D01*
X196843Y209566D01*
X196871Y209383D01*
X196899Y209214D01*
X196927Y209058D01*
X196941Y208932D01*
X196956Y208833D01*
Y208678D01*
X196927Y208241D01*
X196857Y207846D01*
X196772Y207494D01*
X196716Y207353D01*
X196660Y207212D01*
X196603Y207085D01*
X196547Y206972D01*
X196504Y206887D01*
X196462Y206803D01*
X196420Y206747D01*
X196392Y206704D01*
X196363Y206676D01*
Y206662D01*
X196110Y206380D01*
X195842Y206154D01*
X195560Y205957D01*
X195292Y205816D01*
X195052Y205703D01*
X194940Y205661D01*
X194855Y205619D01*
X194771Y205591D01*
X194714Y205576D01*
X194686Y205562D01*
X194672D01*
X194517Y206803D01*
X194785Y206916D01*
X195010Y207043D01*
X195208Y207169D01*
X195363Y207282D01*
X195475Y207381D01*
X195560Y207465D01*
X195616Y207536D01*
X195630Y207550D01*
X195743Y207733D01*
X195828Y207917D01*
X195884Y208114D01*
X195926Y208283D01*
X195955Y208438D01*
X195969Y208565D01*
Y208678D01*
X195955Y208847D01*
X195940Y209002D01*
X195870Y209284D01*
X195771Y209538D01*
X195659Y209763D01*
X195560Y209932D01*
X195461Y210059D01*
X195391Y210144D01*
X195363Y210158D01*
Y210172D01*
X195109Y210369D01*
X194827Y210525D01*
X194517Y210637D01*
X194235Y210722D01*
X193981Y210764D01*
X193868Y210792D01*
X193770Y210807D01*
X193685D01*
X193629Y210821D01*
X193586D01*
X193572D01*
Y205534D01*
X193431Y205520D01*
X193333D01*
X193276D01*
X193262D01*
X192938Y205534D01*
X192642Y205562D01*
X192360Y205605D01*
X192092Y205661D01*
X191852Y205732D01*
X191627Y205802D01*
X191430Y205887D01*
X191246Y205971D01*
X191077Y206056D01*
X190936Y206140D01*
X190823Y206211D01*
X190725Y206281D01*
X190640Y206338D01*
X190584Y206380D01*
X190555Y206408D01*
X190541Y206422D01*
X190372Y206591D01*
X190217Y206775D01*
X190090Y206972D01*
X189977Y207169D01*
X189879Y207367D01*
X189808Y207550D01*
X189738Y207747D01*
X189696Y207917D01*
X189653Y208100D01*
X189625Y208255D01*
X189597Y208396D01*
X189583Y208509D01*
X189569Y208607D01*
Y208748D01*
X189583Y209016D01*
X189611Y209270D01*
X189653Y209510D01*
X189724Y209735D01*
X189794Y209947D01*
X189879Y210144D01*
X189963Y210327D01*
X190062Y210482D01*
X190147Y210637D01*
X190245Y210764D01*
X190330Y210877D01*
X190400Y210962D01*
X190471Y211032D01*
X190513Y211089D01*
X190541Y211117D01*
X190555Y211131D01*
X190753Y211286D01*
X190964Y211427D01*
X191176Y211554D01*
X191401Y211666D01*
X191641Y211751D01*
X191866Y211821D01*
X192318Y211934D01*
X192515Y211977D01*
X192712Y212005D01*
X192882Y212019D01*
X193036Y212033D01*
X193163Y212047D01*
X193248D01*
X193319D01*
X193333D01*
X193643Y212033D01*
D02*
G37*
G36*
X207111Y208593D02*
X207463Y208466D01*
X207745Y208311D01*
X207985Y208156D01*
X208182Y208015D01*
X208309Y207888D01*
X208394Y207804D01*
X208408Y207790D01*
X208422Y207776D01*
X208521Y207635D01*
X208605Y207480D01*
X208746Y207141D01*
X208845Y206789D01*
X208915Y206451D01*
X208944Y206296D01*
X208958Y206154D01*
X208972Y206014D01*
Y205901D01*
X208986Y205802D01*
Y205675D01*
X208972Y205365D01*
X208944Y205097D01*
X208901Y204844D01*
X208845Y204618D01*
X208789Y204435D01*
X208746Y204294D01*
X208718Y204209D01*
X208704Y204195D01*
Y204181D01*
X208577Y203941D01*
X208450Y203744D01*
X208309Y203575D01*
X208182Y203420D01*
X208070Y203307D01*
X207971Y203236D01*
X207915Y203180D01*
X207886Y203166D01*
X207689Y203053D01*
X207477Y202969D01*
X207294Y202898D01*
X207125Y202856D01*
X206970Y202828D01*
X206857Y202813D01*
X206787D01*
X206759D01*
X206533Y202828D01*
X206336Y202856D01*
X206166Y202912D01*
X206011Y202955D01*
X205885Y203011D01*
X205800Y203067D01*
X205744Y203095D01*
X205730Y203110D01*
X205588Y203222D01*
X205462Y203349D01*
X205349Y203476D01*
X205264Y203603D01*
X205194Y203730D01*
X205152Y203814D01*
X205123Y203871D01*
X205109Y203899D01*
X205067Y203998D01*
X205025Y204110D01*
X204926Y204378D01*
X204827Y204674D01*
X204743Y204970D01*
X204658Y205238D01*
X204630Y205365D01*
X204602Y205464D01*
X204573Y205548D01*
X204559Y205619D01*
X204545Y205661D01*
Y205675D01*
X204503Y205830D01*
X204461Y205971D01*
X204433Y206098D01*
X204390Y206211D01*
X204348Y206394D01*
X204306Y206535D01*
X204263Y206634D01*
X204249Y206690D01*
X204235Y206718D01*
Y206733D01*
X204179Y206845D01*
X204137Y206944D01*
X204080Y207029D01*
X204038Y207085D01*
X203996Y207141D01*
X203953Y207169D01*
X203939Y207184D01*
X203925Y207198D01*
X203784Y207282D01*
X203643Y207325D01*
X203587D01*
X203544Y207339D01*
X203516D01*
X203502D01*
X203375Y207325D01*
X203248Y207282D01*
X203136Y207226D01*
X203051Y207155D01*
X202966Y207099D01*
X202910Y207043D01*
X202882Y207000D01*
X202868Y206986D01*
X202769Y206831D01*
X202699Y206648D01*
X202656Y206451D01*
X202614Y206267D01*
X202600Y206084D01*
X202586Y205943D01*
Y205802D01*
X202600Y205562D01*
X202628Y205337D01*
X202684Y205154D01*
X202741Y205013D01*
X202797Y204886D01*
X202854Y204801D01*
X202882Y204745D01*
X202896Y204731D01*
X203023Y204590D01*
X203164Y204491D01*
X203305Y204407D01*
X203432Y204336D01*
X203559Y204294D01*
X203657Y204265D01*
X203714Y204251D01*
X203742D01*
X203587Y203081D01*
X203347Y203138D01*
X203136Y203194D01*
X202952Y203265D01*
X202783Y203335D01*
X202670Y203406D01*
X202572Y203462D01*
X202515Y203490D01*
X202501Y203504D01*
X202360Y203631D01*
X202233Y203772D01*
X202121Y203927D01*
X202022Y204082D01*
X201952Y204223D01*
X201895Y204336D01*
X201867Y204407D01*
X201853Y204421D01*
Y204435D01*
X201768Y204674D01*
X201712Y204928D01*
X201656Y205168D01*
X201627Y205393D01*
X201613Y205605D01*
X201599Y205760D01*
Y206098D01*
X201627Y206296D01*
X201641Y206465D01*
X201670Y206620D01*
X201698Y206747D01*
X201726Y206845D01*
X201740Y206902D01*
X201754Y206930D01*
X201810Y207099D01*
X201867Y207254D01*
X201923Y207381D01*
X201980Y207494D01*
X202022Y207578D01*
X202064Y207635D01*
X202078Y207677D01*
X202092Y207691D01*
X202191Y207832D01*
X202304Y207945D01*
X202431Y208043D01*
X202530Y208128D01*
X202628Y208199D01*
X202699Y208241D01*
X202755Y208269D01*
X202769Y208283D01*
X202924Y208354D01*
X203065Y208410D01*
X203220Y208438D01*
X203347Y208466D01*
X203474Y208480D01*
X203559Y208495D01*
X203615D01*
X203643D01*
X203841Y208480D01*
X204010Y208452D01*
X204179Y208410D01*
X204320Y208368D01*
X204433Y208325D01*
X204531Y208283D01*
X204588Y208255D01*
X204602Y208241D01*
X204757Y208128D01*
X204884Y208001D01*
X204996Y207874D01*
X205095Y207747D01*
X205166Y207635D01*
X205222Y207550D01*
X205250Y207494D01*
X205264Y207465D01*
X205307Y207367D01*
X205363Y207240D01*
X205462Y206958D01*
X205546Y206662D01*
X205645Y206352D01*
X205715Y206084D01*
X205758Y205957D01*
X205786Y205844D01*
X205814Y205760D01*
X205828Y205689D01*
X205842Y205647D01*
Y205633D01*
X205885Y205450D01*
X205927Y205295D01*
X205969Y205154D01*
X206011Y205027D01*
X206040Y204914D01*
X206082Y204815D01*
X206138Y204646D01*
X206181Y204533D01*
X206223Y204463D01*
X206237Y204421D01*
X206251Y204407D01*
X206336Y204280D01*
X206448Y204195D01*
X206547Y204125D01*
X206646Y204082D01*
X206744Y204054D01*
X206815Y204040D01*
X206871D01*
X206885D01*
X207055Y204054D01*
X207196Y204096D01*
X207337Y204167D01*
X207449Y204237D01*
X207548Y204322D01*
X207619Y204378D01*
X207661Y204435D01*
X207675Y204449D01*
X207788Y204618D01*
X207858Y204801D01*
X207915Y205013D01*
X207957Y205210D01*
X207985Y205393D01*
X207999Y205534D01*
Y205675D01*
X207985Y205971D01*
X207943Y206225D01*
X207886Y206436D01*
X207816Y206620D01*
X207745Y206761D01*
X207689Y206873D01*
X207647Y206930D01*
X207633Y206958D01*
X207477Y207113D01*
X207294Y207240D01*
X207111Y207325D01*
X206942Y207395D01*
X206787Y207451D01*
X206646Y207480D01*
X206561Y207508D01*
X206547D01*
X206533D01*
X206716Y208692D01*
X207111Y208593D01*
D02*
G37*
G36*
X195081Y204435D02*
X195433Y204308D01*
X195715Y204153D01*
X195955Y203998D01*
X196152Y203857D01*
X196279Y203730D01*
X196363Y203645D01*
X196378Y203631D01*
X196392Y203617D01*
X196490Y203476D01*
X196575Y203321D01*
X196716Y202983D01*
X196814Y202630D01*
X196885Y202292D01*
X196913Y202137D01*
X196927Y201996D01*
X196941Y201855D01*
Y201742D01*
X196956Y201644D01*
Y201517D01*
X196941Y201206D01*
X196913Y200939D01*
X196871Y200685D01*
X196814Y200459D01*
X196758Y200276D01*
X196716Y200135D01*
X196688Y200051D01*
X196674Y200036D01*
Y200022D01*
X196547Y199783D01*
X196420Y199585D01*
X196279Y199416D01*
X196152Y199261D01*
X196039Y199148D01*
X195940Y199078D01*
X195884Y199021D01*
X195856Y199007D01*
X195659Y198895D01*
X195447Y198810D01*
X195264Y198739D01*
X195095Y198697D01*
X194940Y198669D01*
X194827Y198655D01*
X194756D01*
X194728D01*
X194503Y198669D01*
X194305Y198697D01*
X194136Y198754D01*
X193981Y198796D01*
X193854Y198852D01*
X193770Y198909D01*
X193713Y198937D01*
X193699Y198951D01*
X193558Y199064D01*
X193431Y199191D01*
X193319Y199317D01*
X193234Y199444D01*
X193163Y199571D01*
X193121Y199656D01*
X193093Y199712D01*
X193079Y199740D01*
X193036Y199839D01*
X192994Y199952D01*
X192896Y200220D01*
X192797Y200516D01*
X192712Y200812D01*
X192628Y201080D01*
X192600Y201206D01*
X192571Y201305D01*
X192543Y201390D01*
X192529Y201460D01*
X192515Y201502D01*
Y201517D01*
X192473Y201672D01*
X192430Y201813D01*
X192402Y201940D01*
X192360Y202052D01*
X192318Y202236D01*
X192275Y202376D01*
X192233Y202475D01*
X192219Y202532D01*
X192205Y202560D01*
Y202574D01*
X192148Y202687D01*
X192106Y202785D01*
X192050Y202870D01*
X192008Y202926D01*
X191965Y202983D01*
X191923Y203011D01*
X191909Y203025D01*
X191895Y203039D01*
X191754Y203124D01*
X191613Y203166D01*
X191556D01*
X191514Y203180D01*
X191486D01*
X191472D01*
X191345Y203166D01*
X191218Y203124D01*
X191105Y203067D01*
X191021Y202997D01*
X190936Y202940D01*
X190880Y202884D01*
X190851Y202842D01*
X190837Y202828D01*
X190739Y202673D01*
X190668Y202489D01*
X190626Y202292D01*
X190584Y202109D01*
X190570Y201925D01*
X190555Y201784D01*
Y201644D01*
X190570Y201404D01*
X190598Y201178D01*
X190654Y200995D01*
X190711Y200854D01*
X190767Y200727D01*
X190823Y200643D01*
X190851Y200586D01*
X190866Y200572D01*
X190993Y200431D01*
X191133Y200332D01*
X191274Y200248D01*
X191401Y200177D01*
X191528Y200135D01*
X191627Y200107D01*
X191683Y200093D01*
X191711D01*
X191556Y198923D01*
X191317Y198979D01*
X191105Y199035D01*
X190922Y199106D01*
X190753Y199177D01*
X190640Y199247D01*
X190541Y199303D01*
X190485Y199332D01*
X190471Y199346D01*
X190330Y199473D01*
X190203Y199613D01*
X190090Y199769D01*
X189992Y199924D01*
X189921Y200065D01*
X189865Y200177D01*
X189837Y200248D01*
X189822Y200262D01*
Y200276D01*
X189738Y200516D01*
X189681Y200769D01*
X189625Y201009D01*
X189597Y201235D01*
X189583Y201446D01*
X189569Y201601D01*
Y201940D01*
X189597Y202137D01*
X189611Y202306D01*
X189639Y202461D01*
X189667Y202588D01*
X189696Y202687D01*
X189710Y202743D01*
X189724Y202771D01*
X189780Y202940D01*
X189837Y203095D01*
X189893Y203222D01*
X189949Y203335D01*
X189992Y203420D01*
X190034Y203476D01*
X190048Y203518D01*
X190062Y203533D01*
X190161Y203673D01*
X190273Y203786D01*
X190400Y203885D01*
X190499Y203969D01*
X190598Y204040D01*
X190668Y204082D01*
X190725Y204110D01*
X190739Y204125D01*
X190894Y204195D01*
X191035Y204251D01*
X191190Y204280D01*
X191317Y204308D01*
X191444Y204322D01*
X191528Y204336D01*
X191585D01*
X191613D01*
X191810Y204322D01*
X191979Y204294D01*
X192148Y204251D01*
X192289Y204209D01*
X192402Y204167D01*
X192501Y204125D01*
X192557Y204096D01*
X192571Y204082D01*
X192726Y203969D01*
X192853Y203843D01*
X192966Y203716D01*
X193065Y203589D01*
X193135Y203476D01*
X193192Y203391D01*
X193220Y203335D01*
X193234Y203307D01*
X193276Y203208D01*
X193333Y203081D01*
X193431Y202799D01*
X193516Y202503D01*
X193615Y202193D01*
X193685Y201925D01*
X193727Y201798D01*
X193755Y201686D01*
X193784Y201601D01*
X193798Y201531D01*
X193812Y201488D01*
Y201474D01*
X193854Y201291D01*
X193897Y201136D01*
X193939Y200995D01*
X193981Y200868D01*
X194009Y200755D01*
X194051Y200657D01*
X194108Y200487D01*
X194150Y200375D01*
X194193Y200304D01*
X194207Y200262D01*
X194221Y200248D01*
X194305Y200121D01*
X194418Y200036D01*
X194517Y199966D01*
X194615Y199924D01*
X194714Y199895D01*
X194785Y199881D01*
X194841D01*
X194855D01*
X195024Y199895D01*
X195165Y199938D01*
X195306Y200008D01*
X195419Y200079D01*
X195518Y200163D01*
X195588Y200220D01*
X195630Y200276D01*
X195644Y200290D01*
X195757Y200459D01*
X195828Y200643D01*
X195884Y200854D01*
X195926Y201051D01*
X195955Y201235D01*
X195969Y201376D01*
Y201517D01*
X195955Y201813D01*
X195912Y202066D01*
X195856Y202278D01*
X195786Y202461D01*
X195715Y202602D01*
X195659Y202715D01*
X195616Y202771D01*
X195602Y202799D01*
X195447Y202955D01*
X195264Y203081D01*
X195081Y203166D01*
X194911Y203236D01*
X194756Y203293D01*
X194615Y203321D01*
X194531Y203349D01*
X194517D01*
X194503D01*
X194686Y204533D01*
X195081Y204435D01*
D02*
G37*
%LPC*%
G36*
X60598Y316487D02*
X54281D01*
Y316350D01*
X54007D01*
Y316213D01*
X53869D01*
Y315801D01*
X53732D01*
Y294654D01*
X53869D01*
Y294517D01*
X53732D01*
Y294242D01*
X53869D01*
Y293967D01*
X54007D01*
Y293830D01*
X54144D01*
Y293693D01*
X54556D01*
Y293555D01*
X60323D01*
Y293693D01*
X60735D01*
Y293830D01*
X60872D01*
Y293967D01*
X61010D01*
Y294379D01*
X61147D01*
Y300970D01*
X61284D01*
Y301108D01*
X61422D01*
Y301245D01*
X82980D01*
Y301383D01*
X83392D01*
Y301520D01*
X83530D01*
Y301657D01*
X83667D01*
Y308386D01*
X83530D01*
Y308523D01*
X83392D01*
Y308660D01*
X83255D01*
Y308798D01*
X61696D01*
Y308935D01*
X61422D01*
Y309072D01*
X61284D01*
Y309210D01*
X61147D01*
Y315801D01*
X61010D01*
Y316075D01*
X60872D01*
Y316213D01*
X60735D01*
Y316350D01*
X60598D01*
Y316487D01*
D02*
G37*
G36*
X83118Y291908D02*
X54418D01*
Y291770D01*
X54144D01*
Y291633D01*
X53869D01*
Y291221D01*
X53732D01*
Y284904D01*
X53869D01*
Y284630D01*
X54007D01*
Y284492D01*
X54144D01*
Y284355D01*
X83392D01*
Y284492D01*
X83530D01*
Y284630D01*
X83667D01*
Y291496D01*
X83530D01*
Y291633D01*
X83392D01*
Y291770D01*
X83118D01*
Y291908D01*
D02*
G37*
G36*
X111131Y291084D02*
X91220D01*
Y290946D01*
X90670D01*
Y290809D01*
X90396D01*
Y290672D01*
X90258D01*
Y290534D01*
X90121D01*
Y290397D01*
X89984D01*
Y290260D01*
X89846D01*
Y290122D01*
X89709D01*
Y289985D01*
X89572D01*
Y289848D01*
X89434D01*
Y289711D01*
X89297D01*
Y289573D01*
X89160D01*
Y289436D01*
X89022D01*
Y289298D01*
X88885D01*
Y289161D01*
X88748D01*
Y289024D01*
X88610D01*
Y288887D01*
X88473D01*
Y288749D01*
X88336D01*
Y288612D01*
X88198D01*
Y288475D01*
X88061D01*
Y288337D01*
X87924D01*
Y288200D01*
X87787D01*
Y288063D01*
X87649D01*
Y287925D01*
X87512D01*
Y287788D01*
X87375D01*
Y287651D01*
X87237D01*
Y287513D01*
X87100D01*
Y287376D01*
X86963D01*
Y287239D01*
X86825D01*
Y287101D01*
X86688D01*
Y286964D01*
X86551D01*
Y286689D01*
X86413D01*
Y286278D01*
X86276D01*
Y285866D01*
X86139D01*
Y269387D01*
X86276D01*
Y269250D01*
X86139D01*
Y268976D01*
X86276D01*
Y268564D01*
X86413D01*
Y268426D01*
X86551D01*
Y268289D01*
X93142D01*
Y268426D01*
X93279D01*
Y268564D01*
X93417D01*
Y268976D01*
X93554D01*
Y269525D01*
X93417D01*
Y269662D01*
X93554D01*
Y283257D01*
X93691D01*
Y283394D01*
X93828D01*
Y283531D01*
X108384D01*
Y283394D01*
X108659D01*
Y283119D01*
X108796D01*
Y268838D01*
X108933D01*
Y268564D01*
X109071D01*
Y268426D01*
X109208D01*
Y268289D01*
X115662D01*
Y268426D01*
X115799D01*
Y268564D01*
X115937D01*
Y268701D01*
X116074D01*
Y286140D01*
X115937D01*
Y286552D01*
X115799D01*
Y286827D01*
X115662D01*
Y286964D01*
X115525D01*
Y287101D01*
X115387D01*
Y287239D01*
X115250D01*
Y287376D01*
X115113D01*
Y287513D01*
X114975D01*
Y287651D01*
X114838D01*
Y287788D01*
X114701D01*
Y287925D01*
X114564D01*
Y288063D01*
X114426D01*
Y288200D01*
X114289D01*
Y288337D01*
X114151D01*
Y288475D01*
X114014D01*
Y288612D01*
X113877D01*
Y288749D01*
X113740D01*
Y288887D01*
X113602D01*
Y289024D01*
X113465D01*
Y289161D01*
X113328D01*
Y289298D01*
X113190D01*
Y289436D01*
X113053D01*
Y289573D01*
X112916D01*
Y289711D01*
X112778D01*
Y289848D01*
X112641D01*
Y289985D01*
X112504D01*
Y290122D01*
X112366D01*
Y290260D01*
X112229D01*
Y290397D01*
X112092D01*
Y290534D01*
X111954D01*
Y290672D01*
X111817D01*
Y290809D01*
X111543D01*
Y290946D01*
X111131D01*
Y291084D01*
D02*
G37*
G36*
X83255Y280922D02*
X54281D01*
Y280785D01*
X54007D01*
Y280648D01*
X53869D01*
Y280236D01*
X53732D01*
Y259226D01*
X61147D01*
Y259638D01*
X61010D01*
Y259775D01*
X61147D01*
Y261698D01*
X83255D01*
Y261835D01*
X83392D01*
Y261972D01*
X83530D01*
Y262110D01*
X83667D01*
Y268152D01*
X83530D01*
Y268426D01*
X83392D01*
Y268564D01*
X83118D01*
Y268701D01*
X61147D01*
Y273370D01*
X83118D01*
Y273507D01*
X83392D01*
Y273644D01*
X83530D01*
Y273782D01*
X83667D01*
Y280510D01*
X83530D01*
Y280785D01*
X83255D01*
Y280922D01*
D02*
G37*
G36*
X103715Y271585D02*
X97536D01*
Y271447D01*
X97261D01*
Y271310D01*
X96987D01*
Y271173D01*
X96849D01*
Y271035D01*
X96575D01*
Y270898D01*
X96438D01*
Y270761D01*
X96300D01*
Y270623D01*
X96163D01*
Y270486D01*
X96026D01*
Y270349D01*
X95888D01*
Y270211D01*
X95751D01*
Y270074D01*
X95614D01*
Y269937D01*
X95476D01*
Y269799D01*
X95339D01*
Y269662D01*
X95202D01*
Y269525D01*
X95064D01*
Y269387D01*
X94927D01*
Y269250D01*
X94790D01*
Y269113D01*
X94652D01*
Y268976D01*
X94515D01*
Y268838D01*
X94378D01*
Y268564D01*
X94241D01*
Y268426D01*
X94103D01*
Y268289D01*
X93966D01*
Y268152D01*
X93828D01*
Y268014D01*
X93691D01*
Y267877D01*
X93554D01*
Y267740D01*
X93417D01*
Y267602D01*
X93279D01*
Y267465D01*
X93142D01*
Y267328D01*
X93005D01*
Y267190D01*
X92867D01*
Y267053D01*
X92730D01*
Y266916D01*
X92593D01*
Y266779D01*
X92455D01*
Y266641D01*
X92318D01*
Y266504D01*
X92181D01*
Y266367D01*
X92043D01*
Y266229D01*
X91906D01*
Y266092D01*
X91769D01*
Y265955D01*
X91631D01*
Y265817D01*
X91494D01*
Y265680D01*
X91357D01*
Y265543D01*
X91220D01*
Y265405D01*
X91082D01*
Y265268D01*
X90945D01*
Y265131D01*
X90808D01*
Y264993D01*
X90670D01*
Y264856D01*
X90533D01*
Y264719D01*
X90396D01*
Y264581D01*
X90258D01*
Y264444D01*
X90121D01*
Y264307D01*
X89984D01*
Y264169D01*
X89846D01*
Y264032D01*
X89709D01*
Y263895D01*
X89572D01*
Y263757D01*
X89434D01*
Y263620D01*
X89297D01*
Y263483D01*
X89160D01*
Y263346D01*
X89022D01*
Y263208D01*
X88885D01*
Y263071D01*
X88748D01*
Y262934D01*
X88610D01*
Y262796D01*
X88473D01*
Y262659D01*
X88336D01*
Y262522D01*
X88198D01*
Y262384D01*
X88061D01*
Y262247D01*
X87924D01*
Y262110D01*
X87787D01*
Y261972D01*
X87649D01*
Y261835D01*
X87512D01*
Y261698D01*
X87375D01*
Y261560D01*
X87237D01*
Y261423D01*
X87100D01*
Y261286D01*
X86963D01*
Y261148D01*
X86825D01*
Y261011D01*
X86688D01*
Y260874D01*
X86551D01*
Y260737D01*
X86413D01*
Y260599D01*
X86276D01*
Y260462D01*
X86139D01*
Y260324D01*
X86001D01*
Y260187D01*
X85864D01*
Y260050D01*
X85727D01*
Y259913D01*
X85590D01*
Y259775D01*
X85452D01*
Y259638D01*
X85315D01*
Y259501D01*
X85177D01*
Y259226D01*
X85040D01*
Y259089D01*
X84903D01*
Y258951D01*
X84766D01*
Y258814D01*
X84628D01*
Y258677D01*
X84491D01*
Y258539D01*
X84354D01*
Y258402D01*
X84216D01*
Y258265D01*
X84079D01*
Y258127D01*
X83942D01*
Y257990D01*
X83804D01*
Y257853D01*
X83667D01*
Y257715D01*
X83530D01*
Y257578D01*
X83392D01*
Y257441D01*
X83255D01*
Y257304D01*
X83118D01*
Y257166D01*
X82980D01*
Y257029D01*
X82843D01*
Y256892D01*
X37391D01*
Y254420D01*
X37528D01*
Y253871D01*
X37666D01*
Y253596D01*
X37803D01*
Y253459D01*
X37940D01*
Y253321D01*
X38078D01*
Y253184D01*
X38215D01*
Y253047D01*
X38352D01*
Y252909D01*
X38490D01*
Y252772D01*
X38627D01*
Y252635D01*
X38764D01*
Y252497D01*
X38902D01*
Y252360D01*
X39039D01*
Y252223D01*
X39176D01*
Y252085D01*
X39313D01*
Y251948D01*
X39451D01*
Y251811D01*
X39588D01*
Y251674D01*
X39725D01*
Y251536D01*
X39863D01*
Y251399D01*
X40000D01*
Y251262D01*
X40137D01*
Y251124D01*
X40275D01*
Y250987D01*
X40412D01*
Y250850D01*
X40549D01*
Y250712D01*
X40687D01*
Y250575D01*
X40824D01*
Y250438D01*
X40961D01*
Y250300D01*
X41099D01*
Y250163D01*
X41236D01*
Y250026D01*
X41373D01*
Y249888D01*
X41511D01*
Y249751D01*
X41785D01*
Y249614D01*
X42334D01*
Y249477D01*
X85040D01*
Y249614D01*
X85590D01*
Y249751D01*
X85864D01*
Y249888D01*
X86139D01*
Y250026D01*
X86413D01*
Y250163D01*
X86551D01*
Y250300D01*
X86825D01*
Y250438D01*
X86963D01*
Y250575D01*
X87100D01*
Y250712D01*
X87237D01*
Y250850D01*
X87375D01*
Y250987D01*
X87512D01*
Y251124D01*
X87649D01*
Y251262D01*
X87787D01*
Y251399D01*
X87924D01*
Y251536D01*
X88061D01*
Y251674D01*
X88198D01*
Y251811D01*
X88336D01*
Y251948D01*
X88473D01*
Y252085D01*
X88610D01*
Y252223D01*
X88748D01*
Y252360D01*
X88885D01*
Y252497D01*
X89022D01*
Y252635D01*
X89160D01*
Y252772D01*
X89297D01*
Y252909D01*
X89434D01*
Y253047D01*
X89572D01*
Y253184D01*
X89709D01*
Y253321D01*
X89846D01*
Y253459D01*
X89984D01*
Y253596D01*
X90121D01*
Y253733D01*
X90258D01*
Y253871D01*
X90396D01*
Y254008D01*
X90533D01*
Y254145D01*
X90670D01*
Y254283D01*
X90808D01*
Y254420D01*
X90945D01*
Y254694D01*
X91082D01*
Y254832D01*
X91220D01*
Y254969D01*
X91357D01*
Y255107D01*
X91494D01*
Y255244D01*
X91631D01*
Y255381D01*
X91769D01*
Y255518D01*
X91906D01*
Y255656D01*
X92043D01*
Y255793D01*
X92181D01*
Y255930D01*
X92318D01*
Y256068D01*
X92455D01*
Y256205D01*
X92593D01*
Y256342D01*
X92730D01*
Y256480D01*
X92867D01*
Y256617D01*
X93005D01*
Y256754D01*
X93142D01*
Y256892D01*
X93279D01*
Y257029D01*
X93417D01*
Y257166D01*
X93554D01*
Y257304D01*
X93691D01*
Y257441D01*
X93828D01*
Y257578D01*
X93966D01*
Y257715D01*
X94103D01*
Y257853D01*
X94241D01*
Y257990D01*
X94378D01*
Y258127D01*
X94515D01*
Y258265D01*
X94652D01*
Y258402D01*
X94790D01*
Y258539D01*
X94927D01*
Y258677D01*
X95064D01*
Y258814D01*
X95202D01*
Y258951D01*
X95339D01*
Y259089D01*
X95476D01*
Y259226D01*
X95614D01*
Y259363D01*
X95751D01*
Y259501D01*
X95888D01*
Y259638D01*
X96026D01*
Y259775D01*
X96163D01*
Y259913D01*
X96300D01*
Y260050D01*
X96438D01*
Y260187D01*
X96575D01*
Y260324D01*
X96712D01*
Y260462D01*
X96849D01*
Y260599D01*
X96987D01*
Y260737D01*
X97124D01*
Y260874D01*
X97261D01*
Y261011D01*
X97399D01*
Y261148D01*
X97536D01*
Y261286D01*
X97673D01*
Y261423D01*
X97811D01*
Y261560D01*
X97948D01*
Y261698D01*
X98085D01*
Y261835D01*
X98223D01*
Y261972D01*
X98360D01*
Y262110D01*
X98497D01*
Y262247D01*
X98635D01*
Y262384D01*
X98772D01*
Y262522D01*
X98909D01*
Y262659D01*
X99047D01*
Y262796D01*
X99184D01*
Y262934D01*
X99321D01*
Y263071D01*
X99459D01*
Y263208D01*
X99596D01*
Y263346D01*
X99733D01*
Y263483D01*
X99871D01*
Y263620D01*
X100008D01*
Y263757D01*
X100145D01*
Y263895D01*
X100282D01*
Y264032D01*
X100420D01*
Y264169D01*
X100557D01*
Y264307D01*
X100694D01*
Y264444D01*
X100832D01*
Y264581D01*
X100969D01*
Y264719D01*
X101106D01*
Y264856D01*
X101244D01*
Y264993D01*
X101381D01*
Y265131D01*
X101518D01*
Y265268D01*
X101656D01*
Y265405D01*
X101793D01*
Y265543D01*
X101930D01*
Y265680D01*
X102068D01*
Y265817D01*
X102205D01*
Y265955D01*
X102342D01*
Y266092D01*
X102480D01*
Y266367D01*
X102617D01*
Y266504D01*
X102754D01*
Y266641D01*
X102892D01*
Y266779D01*
X103029D01*
Y266916D01*
X103166D01*
Y267053D01*
X103303D01*
Y267190D01*
X103441D01*
Y267328D01*
X103578D01*
Y267465D01*
X103715D01*
Y267602D01*
X103853D01*
Y267740D01*
X103990D01*
Y267877D01*
X104127D01*
Y268014D01*
X104265D01*
Y268152D01*
X104402D01*
Y268289D01*
X104539D01*
Y268426D01*
X104677D01*
Y268564D01*
X104814D01*
Y268701D01*
X104951D01*
Y268838D01*
X105089D01*
Y268976D01*
X105226D01*
Y269113D01*
X105363D01*
Y269250D01*
X105500D01*
Y269387D01*
X105638D01*
Y269525D01*
X105775D01*
Y269799D01*
X105638D01*
Y269937D01*
X105500D01*
Y270074D01*
X105363D01*
Y270211D01*
X105226D01*
Y270349D01*
X105089D01*
Y270486D01*
X104951D01*
Y270623D01*
X104814D01*
Y270761D01*
X104677D01*
Y270898D01*
X104539D01*
Y271035D01*
X104265D01*
Y271173D01*
X104127D01*
Y271310D01*
X103853D01*
Y271447D01*
X103715D01*
Y271585D01*
D02*
G37*
G36*
X115662Y264856D02*
X104677D01*
Y264719D01*
X104539D01*
Y264581D01*
X104402D01*
Y264444D01*
X104265D01*
Y264307D01*
X104127D01*
Y264169D01*
X103990D01*
Y264032D01*
X103853D01*
Y263757D01*
X103715D01*
Y263620D01*
X103578D01*
Y263483D01*
X103441D01*
Y263346D01*
X103303D01*
Y263208D01*
X103166D01*
Y263071D01*
X103029D01*
Y262934D01*
X102892D01*
Y262796D01*
X102754D01*
Y262659D01*
X102617D01*
Y262522D01*
X102480D01*
Y262384D01*
X102342D01*
Y262247D01*
X102205D01*
Y262110D01*
X102068D01*
Y261972D01*
X101930D01*
Y261835D01*
X101793D01*
Y261698D01*
X101656D01*
Y261560D01*
X101518D01*
Y261423D01*
X101381D01*
Y261286D01*
X101244D01*
Y261148D01*
X101106D01*
Y261011D01*
X100969D01*
Y260874D01*
X100832D01*
Y260737D01*
X100694D01*
Y260599D01*
X100557D01*
Y260462D01*
X100420D01*
Y260324D01*
X100282D01*
Y260187D01*
X100145D01*
Y260050D01*
X100008D01*
Y259913D01*
X99871D01*
Y259775D01*
X99733D01*
Y259638D01*
X99596D01*
Y259501D01*
X99459D01*
Y259363D01*
X99321D01*
Y259226D01*
X99184D01*
Y259089D01*
X99047D01*
Y258951D01*
X98909D01*
Y258814D01*
X98772D01*
Y258677D01*
X98635D01*
Y258539D01*
X98497D01*
Y258402D01*
X98360D01*
Y258265D01*
X98223D01*
Y258127D01*
X98085D01*
Y257990D01*
X97948D01*
Y257853D01*
X97811D01*
Y257715D01*
X97673D01*
Y257578D01*
X97536D01*
Y257441D01*
X97399D01*
Y257304D01*
X100420D01*
Y247279D01*
X92867D01*
Y253459D01*
X92730D01*
Y253321D01*
X92593D01*
Y253184D01*
X92455D01*
Y253047D01*
X92318D01*
Y252909D01*
X92181D01*
Y252772D01*
X92043D01*
Y252635D01*
X91906D01*
Y252497D01*
X91769D01*
Y252360D01*
X91631D01*
Y252223D01*
X91494D01*
Y252085D01*
X91357D01*
Y251948D01*
X91220D01*
Y251811D01*
X91082D01*
Y251674D01*
X90945D01*
Y251536D01*
X90808D01*
Y251399D01*
X90670D01*
Y251262D01*
X90533D01*
Y251124D01*
X90396D01*
Y250987D01*
X90258D01*
Y250850D01*
X90121D01*
Y250712D01*
X89984D01*
Y250575D01*
X89846D01*
Y250438D01*
X89709D01*
Y250300D01*
X89572D01*
Y250163D01*
X89434D01*
Y250026D01*
X89297D01*
Y249888D01*
X89160D01*
Y249751D01*
X89022D01*
Y249614D01*
X88885D01*
Y249477D01*
X88748D01*
Y249339D01*
X88610D01*
Y249202D01*
X88473D01*
Y249065D01*
X88336D01*
Y248927D01*
X88198D01*
Y248790D01*
X88061D01*
Y248653D01*
X87924D01*
Y248515D01*
X87787D01*
Y248378D01*
X87649D01*
Y248241D01*
X87512D01*
Y248103D01*
X87375D01*
Y247966D01*
X87237D01*
Y247829D01*
X87100D01*
Y247691D01*
X86963D01*
Y247554D01*
X86825D01*
Y247417D01*
X86688D01*
Y247279D01*
X86551D01*
Y247142D01*
X86413D01*
Y247005D01*
X86276D01*
Y246867D01*
X86139D01*
Y244945D01*
X86276D01*
Y244396D01*
X86413D01*
Y244121D01*
X86551D01*
Y243846D01*
X86688D01*
Y243709D01*
X86825D01*
Y243572D01*
X86963D01*
Y243435D01*
X87100D01*
Y243297D01*
X87237D01*
Y243160D01*
X87375D01*
Y243022D01*
X87512D01*
Y242885D01*
X87649D01*
Y242748D01*
X87787D01*
Y242611D01*
X87924D01*
Y242473D01*
X88061D01*
Y242336D01*
X88198D01*
Y242199D01*
X88336D01*
Y242061D01*
X88473D01*
Y241924D01*
X88610D01*
Y241787D01*
X88748D01*
Y241649D01*
X88885D01*
Y241512D01*
X89022D01*
Y241375D01*
X89160D01*
Y241237D01*
X89297D01*
Y241100D01*
X89434D01*
Y240963D01*
X89572D01*
Y240826D01*
X89709D01*
Y240688D01*
X89846D01*
Y240551D01*
X89984D01*
Y240413D01*
X90121D01*
Y240276D01*
X90258D01*
Y240139D01*
X90396D01*
Y240002D01*
X90808D01*
Y239864D01*
X91357D01*
Y239727D01*
X115525D01*
Y239864D01*
X115799D01*
Y240002D01*
X115937D01*
Y240276D01*
X116074D01*
Y246730D01*
X115937D01*
Y247005D01*
X115799D01*
Y247142D01*
X115662D01*
Y247279D01*
X107286D01*
Y247417D01*
X107011D01*
Y247691D01*
X106874D01*
Y256892D01*
X107011D01*
Y257166D01*
X107286D01*
Y257304D01*
X115525D01*
Y257441D01*
X115799D01*
Y257578D01*
X115937D01*
Y257853D01*
X116074D01*
Y264307D01*
X115937D01*
Y264581D01*
X115799D01*
Y264719D01*
X115662D01*
Y264856D01*
D02*
G37*
G36*
X115387Y236843D02*
X115250D01*
Y236706D01*
X115113D01*
Y236843D01*
X86963D01*
Y236706D01*
X86551D01*
Y236569D01*
X86413D01*
Y236431D01*
X86276D01*
Y236157D01*
X86139D01*
Y217207D01*
X86276D01*
Y216520D01*
X86413D01*
Y216108D01*
X86551D01*
Y215834D01*
X86688D01*
Y215696D01*
X86825D01*
Y215559D01*
X86963D01*
Y215422D01*
X87100D01*
Y215284D01*
X87237D01*
Y215147D01*
X87375D01*
Y215010D01*
X87512D01*
Y214872D01*
X87649D01*
Y214735D01*
X87787D01*
Y214598D01*
X87924D01*
Y214461D01*
X88061D01*
Y214323D01*
X88198D01*
Y214186D01*
X88336D01*
Y214049D01*
X88473D01*
Y213911D01*
X88610D01*
Y213774D01*
X88748D01*
Y213637D01*
X88885D01*
Y213499D01*
X89022D01*
Y213362D01*
X89160D01*
Y213225D01*
X89297D01*
Y213087D01*
X89434D01*
Y212950D01*
X89572D01*
Y212813D01*
X89709D01*
Y212675D01*
X89846D01*
Y212538D01*
X89984D01*
Y212401D01*
X90121D01*
Y212263D01*
X90258D01*
Y212126D01*
X90396D01*
Y211989D01*
X90670D01*
Y211852D01*
X91082D01*
Y211714D01*
X101930D01*
Y211852D01*
X102205D01*
Y211989D01*
X102480D01*
Y212126D01*
X102617D01*
Y212263D01*
X102754D01*
Y212401D01*
X102892D01*
Y212538D01*
X103029D01*
Y212675D01*
X103166D01*
Y212813D01*
X103441D01*
Y212950D01*
X103578D01*
Y213087D01*
X103715D01*
Y213225D01*
X103853D01*
Y213362D01*
X103990D01*
Y213499D01*
X104127D01*
Y213637D01*
X104265D01*
Y213774D01*
X104402D01*
Y213911D01*
X104539D01*
Y214049D01*
X104677D01*
Y214186D01*
X104814D01*
Y214323D01*
X104951D01*
Y214461D01*
X105089D01*
Y214598D01*
X105226D01*
Y214735D01*
X105363D01*
Y214872D01*
X105500D01*
Y215010D01*
X105638D01*
Y215147D01*
X105775D01*
Y215284D01*
X105913D01*
Y215422D01*
X106050D01*
Y215559D01*
X106187D01*
Y215696D01*
X106324D01*
Y215834D01*
X106462D01*
Y215971D01*
X106736D01*
Y215834D01*
X106874D01*
Y215696D01*
X107148D01*
Y215559D01*
X107423D01*
Y215422D01*
X107560D01*
Y215284D01*
X107835D01*
Y215147D01*
X108110D01*
Y215010D01*
X108384D01*
Y214872D01*
X108521D01*
Y214735D01*
X108796D01*
Y214598D01*
X109071D01*
Y214461D01*
X109208D01*
Y214323D01*
X109483D01*
Y214186D01*
X109757D01*
Y214049D01*
X109895D01*
Y213911D01*
X110169D01*
Y213774D01*
X110444D01*
Y213637D01*
X110581D01*
Y213499D01*
X110856D01*
Y213362D01*
X111131D01*
Y213225D01*
X111268D01*
Y213087D01*
X111543D01*
Y212950D01*
X111817D01*
Y212813D01*
X111954D01*
Y212675D01*
X112229D01*
Y212538D01*
X112504D01*
Y212401D01*
X112641D01*
Y212263D01*
X112916D01*
Y212126D01*
X113190D01*
Y211989D01*
X113328D01*
Y211852D01*
X113602D01*
Y211714D01*
X113877D01*
Y211577D01*
X114014D01*
Y211439D01*
X114289D01*
Y211302D01*
X114564D01*
Y211165D01*
X114701D01*
Y211028D01*
X114975D01*
Y210890D01*
X115250D01*
Y210753D01*
X115387D01*
Y210616D01*
X115937D01*
Y210753D01*
X116074D01*
Y218443D01*
X115937D01*
Y218717D01*
X115799D01*
Y218855D01*
X115662D01*
Y218992D01*
X115525D01*
Y219129D01*
X115387D01*
Y219267D01*
X115113D01*
Y219404D01*
X114838D01*
Y219541D01*
X114701D01*
Y219679D01*
X114426D01*
Y219816D01*
X114151D01*
Y219953D01*
X113877D01*
Y220091D01*
X113740D01*
Y220228D01*
X113465D01*
Y220365D01*
X113190D01*
Y220502D01*
X113053D01*
Y220640D01*
X112778D01*
Y220777D01*
X112504D01*
Y220914D01*
X112366D01*
Y221052D01*
X112092D01*
Y221189D01*
X111817D01*
Y221326D01*
X111680D01*
Y221464D01*
X111405D01*
Y221601D01*
X111131D01*
Y221738D01*
X110856D01*
Y221876D01*
X110719D01*
Y222013D01*
X110444D01*
Y222150D01*
X110169D01*
Y222288D01*
X110032D01*
Y222425D01*
X109757D01*
Y222562D01*
X109483D01*
Y222700D01*
X109345D01*
Y222837D01*
X109071D01*
Y222974D01*
X108796D01*
Y223111D01*
X108521D01*
Y223249D01*
X108384D01*
Y223386D01*
X108110D01*
Y223524D01*
X107835D01*
Y223661D01*
X107698D01*
Y223798D01*
X107423D01*
Y223935D01*
X107148D01*
Y229153D01*
X107835D01*
Y229291D01*
X107972D01*
Y229153D01*
X115387D01*
Y229291D01*
X115799D01*
Y229428D01*
X115937D01*
Y229565D01*
X116074D01*
Y236294D01*
X115937D01*
Y236569D01*
X115799D01*
Y236706D01*
X115387D01*
Y236843D01*
D02*
G37*
G36*
X78312Y246181D02*
X59225D01*
Y246043D01*
X58538D01*
Y245906D01*
X58126D01*
Y245769D01*
X57989D01*
Y245632D01*
X57851D01*
Y245494D01*
X57714D01*
Y245357D01*
X57577D01*
Y245220D01*
X57439D01*
Y245082D01*
X57302D01*
Y244945D01*
X57165D01*
Y244808D01*
X57027D01*
Y244670D01*
X56890D01*
Y244533D01*
X56753D01*
Y244396D01*
X56616D01*
Y244258D01*
X56478D01*
Y244121D01*
X56341D01*
Y243984D01*
X56203D01*
Y243846D01*
X56066D01*
Y243709D01*
X55929D01*
Y243572D01*
X55792D01*
Y243435D01*
X55654D01*
Y243297D01*
X55517D01*
Y243160D01*
X55380D01*
Y243022D01*
X55242D01*
Y242885D01*
X55105D01*
Y242748D01*
X54968D01*
Y242611D01*
X54830D01*
Y242473D01*
X54693D01*
Y242336D01*
X54556D01*
Y242199D01*
X54418D01*
Y242061D01*
X54281D01*
Y241924D01*
X54144D01*
Y241649D01*
X54007D01*
Y241237D01*
X53869D01*
Y240551D01*
X53732D01*
Y224485D01*
X53869D01*
Y224347D01*
X53732D01*
Y223935D01*
X53869D01*
Y223661D01*
X54007D01*
Y223524D01*
X54144D01*
Y223386D01*
X54418D01*
Y223249D01*
X60323D01*
Y223386D01*
X60460D01*
Y223524D01*
X60598D01*
Y223661D01*
X60735D01*
Y238491D01*
X60872D01*
Y238628D01*
X65679D01*
Y238491D01*
X65816D01*
Y225858D01*
X65953D01*
Y225583D01*
X66228D01*
Y225446D01*
X71308D01*
Y225583D01*
X71583D01*
Y225858D01*
X71720D01*
Y238491D01*
X71858D01*
Y238628D01*
X76526D01*
Y238491D01*
X76664D01*
Y223798D01*
X76801D01*
Y223524D01*
X76939D01*
Y223386D01*
X77213D01*
Y223249D01*
X83118D01*
Y223386D01*
X83392D01*
Y223524D01*
X83530D01*
Y223661D01*
X83667D01*
Y241100D01*
X83530D01*
Y241649D01*
X83392D01*
Y241924D01*
X83255D01*
Y242061D01*
X83118D01*
Y242199D01*
X82980D01*
Y242336D01*
X82843D01*
Y242473D01*
X82706D01*
Y242611D01*
X82569D01*
Y242748D01*
X82431D01*
Y242885D01*
X82294D01*
Y243022D01*
X82157D01*
Y243160D01*
X82019D01*
Y243297D01*
X81882D01*
Y243435D01*
X81745D01*
Y243572D01*
X81607D01*
Y243709D01*
X81470D01*
Y243846D01*
X81333D01*
Y243984D01*
X81195D01*
Y244121D01*
X81058D01*
Y244258D01*
X80921D01*
Y244396D01*
X80783D01*
Y244533D01*
X80646D01*
Y244670D01*
X80509D01*
Y244808D01*
X80371D01*
Y244945D01*
X80234D01*
Y245082D01*
X80097D01*
Y245220D01*
X79960D01*
Y245357D01*
X79822D01*
Y245494D01*
X79685D01*
Y245632D01*
X79548D01*
Y245769D01*
X79273D01*
Y245906D01*
X78998D01*
Y246043D01*
X78312D01*
Y246181D01*
D02*
G37*
G36*
X87787Y305365D02*
X86276D01*
Y303717D01*
X87100D01*
Y303580D01*
X89297D01*
Y303442D01*
X90670D01*
Y303305D01*
X91769D01*
Y303168D01*
X92730D01*
Y303030D01*
X93554D01*
Y302893D01*
X94241D01*
Y302756D01*
X94927D01*
Y302618D01*
X95614D01*
Y302481D01*
X96300D01*
Y302344D01*
X96849D01*
Y302206D01*
X97399D01*
Y302069D01*
X97948D01*
Y301932D01*
X98497D01*
Y301794D01*
X98909D01*
Y301657D01*
X99459D01*
Y301520D01*
X99871D01*
Y301383D01*
X100282D01*
Y301245D01*
X100694D01*
Y301108D01*
X101106D01*
Y300970D01*
X101518D01*
Y300833D01*
X101930D01*
Y300696D01*
X102342D01*
Y300559D01*
X102617D01*
Y300421D01*
X103029D01*
Y300284D01*
X103441D01*
Y300147D01*
X103715D01*
Y300009D01*
X104127D01*
Y299872D01*
X104402D01*
Y299735D01*
X104677D01*
Y299597D01*
X105089D01*
Y299460D01*
X105363D01*
Y299323D01*
X105638D01*
Y299185D01*
X106050D01*
Y299048D01*
X106324D01*
Y298911D01*
X106599D01*
Y298773D01*
X106874D01*
Y298636D01*
X107148D01*
Y298499D01*
X107423D01*
Y298361D01*
X107698D01*
Y298224D01*
X107972D01*
Y298087D01*
X108247D01*
Y297950D01*
X108521D01*
Y297812D01*
X108796D01*
Y297675D01*
X109071D01*
Y297538D01*
X109345D01*
Y297400D01*
X109483D01*
Y297263D01*
X109757D01*
Y297126D01*
X110032D01*
Y296988D01*
X110307D01*
Y296851D01*
X110444D01*
Y296714D01*
X110719D01*
Y296576D01*
X110993D01*
Y296439D01*
X111268D01*
Y296302D01*
X111405D01*
Y296164D01*
X111680D01*
Y296027D01*
X111817D01*
Y295890D01*
X112092D01*
Y295753D01*
X112366D01*
Y295615D01*
X112504D01*
Y295478D01*
X112778D01*
Y295340D01*
X112916D01*
Y295203D01*
X113190D01*
Y295066D01*
X113328D01*
Y294928D01*
X113602D01*
Y294791D01*
X113740D01*
Y294654D01*
X114014D01*
Y294517D01*
X114151D01*
Y294379D01*
X114426D01*
Y294242D01*
X114564D01*
Y294105D01*
X114701D01*
Y293967D01*
X114975D01*
Y293830D01*
X115113D01*
Y293693D01*
X115250D01*
Y293555D01*
X115525D01*
Y293418D01*
X115662D01*
Y293281D01*
X115799D01*
Y293143D01*
X116074D01*
Y293006D01*
X116211D01*
Y292869D01*
X116349D01*
Y292731D01*
X116623D01*
Y292594D01*
X116761D01*
Y292457D01*
X116898D01*
Y292320D01*
X117035D01*
Y292182D01*
X117310D01*
Y292045D01*
X117447D01*
Y291908D01*
X117584D01*
Y291770D01*
X117722D01*
Y291633D01*
X117859D01*
Y291496D01*
X118134D01*
Y291358D01*
X118271D01*
Y291221D01*
X118408D01*
Y291084D01*
X118546D01*
Y290946D01*
X118683D01*
Y290809D01*
X118820D01*
Y290672D01*
X118958D01*
Y290534D01*
X119232D01*
Y290397D01*
X119370D01*
Y290260D01*
X119507D01*
Y290122D01*
X119644D01*
Y289985D01*
X119782D01*
Y289848D01*
X119919D01*
Y289711D01*
X120056D01*
Y289573D01*
X120194D01*
Y289436D01*
X120331D01*
Y289298D01*
X120468D01*
Y289161D01*
X120605D01*
Y289024D01*
X120743D01*
Y288887D01*
X120880D01*
Y288749D01*
X121017D01*
Y288612D01*
X121155D01*
Y288475D01*
X121292D01*
Y288337D01*
X121429D01*
Y288200D01*
X121567D01*
Y288063D01*
X121704D01*
Y287925D01*
X121841D01*
Y287788D01*
X121979D01*
Y287651D01*
X122116D01*
Y287513D01*
X122253D01*
Y287376D01*
X122391D01*
Y287239D01*
X122528D01*
Y287101D01*
X122665D01*
Y286964D01*
X122802D01*
Y286827D01*
X122940D01*
Y286552D01*
X123077D01*
Y286415D01*
X123215D01*
Y286278D01*
X123352D01*
Y286140D01*
X123489D01*
Y286003D01*
X123626D01*
Y285866D01*
X123764D01*
Y285728D01*
X123901D01*
Y285454D01*
X124038D01*
Y285316D01*
X124176D01*
Y285179D01*
X124313D01*
Y285042D01*
X124450D01*
Y284904D01*
X124588D01*
Y284630D01*
X124725D01*
Y284492D01*
X124862D01*
Y284355D01*
X125000D01*
Y284218D01*
X125137D01*
Y283943D01*
X125274D01*
Y283806D01*
X125412D01*
Y283668D01*
X125549D01*
Y283394D01*
X125686D01*
Y283257D01*
X125823D01*
Y283119D01*
X125961D01*
Y282845D01*
X126098D01*
Y282707D01*
X126236D01*
Y282570D01*
X126373D01*
Y282295D01*
X126510D01*
Y282158D01*
X126647D01*
Y282021D01*
X126785D01*
Y281746D01*
X126922D01*
Y281609D01*
X127059D01*
Y281334D01*
X127197D01*
Y281197D01*
X127334D01*
Y280922D01*
X127471D01*
Y280785D01*
X127609D01*
Y280510D01*
X127746D01*
Y280373D01*
X127883D01*
Y280098D01*
X128021D01*
Y279961D01*
X128158D01*
Y279686D01*
X128295D01*
Y279412D01*
X128433D01*
Y279274D01*
X128570D01*
Y279000D01*
X128707D01*
Y278862D01*
X128844D01*
Y278588D01*
X128982D01*
Y278313D01*
X129119D01*
Y278176D01*
X129256D01*
Y277901D01*
X129394D01*
Y277626D01*
X129531D01*
Y277352D01*
X129668D01*
Y277077D01*
X129806D01*
Y276940D01*
X129943D01*
Y276665D01*
X130080D01*
Y276391D01*
X130218D01*
Y276116D01*
X130355D01*
Y275841D01*
X130492D01*
Y275567D01*
X130630D01*
Y275292D01*
X130767D01*
Y275018D01*
X130904D01*
Y274743D01*
X131042D01*
Y274468D01*
X131179D01*
Y274194D01*
X131316D01*
Y273919D01*
X131454D01*
Y273644D01*
X131591D01*
Y273232D01*
X131728D01*
Y272958D01*
X131866D01*
Y272683D01*
X132003D01*
Y272409D01*
X132140D01*
Y271996D01*
X132277D01*
Y271722D01*
X132415D01*
Y271310D01*
X132552D01*
Y271035D01*
X132689D01*
Y270623D01*
X132827D01*
Y270349D01*
X132964D01*
Y269937D01*
X133101D01*
Y269525D01*
X133239D01*
Y269113D01*
X133376D01*
Y268701D01*
X133513D01*
Y268289D01*
X133651D01*
Y267877D01*
X133788D01*
Y267465D01*
X133925D01*
Y267053D01*
X134063D01*
Y266504D01*
X134200D01*
Y266092D01*
X134337D01*
Y265543D01*
X134474D01*
Y264993D01*
X134612D01*
Y264444D01*
X134749D01*
Y263895D01*
X134887D01*
Y263346D01*
X135024D01*
Y262659D01*
X135161D01*
Y261972D01*
X135298D01*
Y261148D01*
X135436D01*
Y260324D01*
X135573D01*
Y259363D01*
X135710D01*
Y258265D01*
X135848D01*
Y257029D01*
X135985D01*
Y254969D01*
X136122D01*
Y249614D01*
X135985D01*
Y249339D01*
X136122D01*
Y249202D01*
X135985D01*
Y247691D01*
X135848D01*
Y246043D01*
X135710D01*
Y245220D01*
X135573D01*
Y244258D01*
X135436D01*
Y243435D01*
X135298D01*
Y242611D01*
X135161D01*
Y241924D01*
X135024D01*
Y241375D01*
X134887D01*
Y240688D01*
X134749D01*
Y240139D01*
X134612D01*
Y239590D01*
X134474D01*
Y239040D01*
X134337D01*
Y238491D01*
X134200D01*
Y238079D01*
X134063D01*
Y237530D01*
X133925D01*
Y237118D01*
X133788D01*
Y236706D01*
X133651D01*
Y236294D01*
X133513D01*
Y235882D01*
X133376D01*
Y235470D01*
X133239D01*
Y235058D01*
X133101D01*
Y234646D01*
X132964D01*
Y234371D01*
X132827D01*
Y233960D01*
X132689D01*
Y233548D01*
X132552D01*
Y233273D01*
X132415D01*
Y232861D01*
X132277D01*
Y232586D01*
X132140D01*
Y232312D01*
X132003D01*
Y231900D01*
X131866D01*
Y231625D01*
X131728D01*
Y231213D01*
X131591D01*
Y230939D01*
X131454D01*
Y230664D01*
X131316D01*
Y230389D01*
X131179D01*
Y230115D01*
X131042D01*
Y229840D01*
X130904D01*
Y229565D01*
X130767D01*
Y229291D01*
X130630D01*
Y229016D01*
X130492D01*
Y228741D01*
X130355D01*
Y228467D01*
X130218D01*
Y228192D01*
X130080D01*
Y227918D01*
X129943D01*
Y227643D01*
X129806D01*
Y227506D01*
X129668D01*
Y227231D01*
X129531D01*
Y226956D01*
X129394D01*
Y226682D01*
X129256D01*
Y226544D01*
X129119D01*
Y226270D01*
X128982D01*
Y225995D01*
X128844D01*
Y225858D01*
X128707D01*
Y225583D01*
X128570D01*
Y225309D01*
X128433D01*
Y225171D01*
X128295D01*
Y224897D01*
X128158D01*
Y224622D01*
X128021D01*
Y224485D01*
X127883D01*
Y224210D01*
X127746D01*
Y224073D01*
X127609D01*
Y223798D01*
X127471D01*
Y223661D01*
X127334D01*
Y223386D01*
X127197D01*
Y223249D01*
X127059D01*
Y222974D01*
X126922D01*
Y222837D01*
X126785D01*
Y222700D01*
X126647D01*
Y222425D01*
X126510D01*
Y222288D01*
X126373D01*
Y222013D01*
X126236D01*
Y221876D01*
X126098D01*
Y221738D01*
X125961D01*
Y221464D01*
X125823D01*
Y221326D01*
X125686D01*
Y221189D01*
X125549D01*
Y220914D01*
X125412D01*
Y220777D01*
X125274D01*
Y220640D01*
X125137D01*
Y220502D01*
X125000D01*
Y220228D01*
X124862D01*
Y220091D01*
X124725D01*
Y219953D01*
X124588D01*
Y219816D01*
X124450D01*
Y219541D01*
X124313D01*
Y219404D01*
X124176D01*
Y219267D01*
X124038D01*
Y219129D01*
X123901D01*
Y218992D01*
X123764D01*
Y218717D01*
X123626D01*
Y218580D01*
X123489D01*
Y218443D01*
X123352D01*
Y218305D01*
X123215D01*
Y218168D01*
X123077D01*
Y218031D01*
X122940D01*
Y217893D01*
X122802D01*
Y217619D01*
X122665D01*
Y217481D01*
X122528D01*
Y217344D01*
X122391D01*
Y217207D01*
X122253D01*
Y217069D01*
X122116D01*
Y216932D01*
X121979D01*
Y216795D01*
X121841D01*
Y216658D01*
X121704D01*
Y216520D01*
X121567D01*
Y216383D01*
X121429D01*
Y216246D01*
X121292D01*
Y216108D01*
X121155D01*
Y215971D01*
X121017D01*
Y215834D01*
X120880D01*
Y215696D01*
X120743D01*
Y215559D01*
X120605D01*
Y215422D01*
X120468D01*
Y215284D01*
X120331D01*
Y215147D01*
X120194D01*
Y215010D01*
X120056D01*
Y214872D01*
X119919D01*
Y214735D01*
X119782D01*
Y214598D01*
X119644D01*
Y214461D01*
X119507D01*
Y214323D01*
X119370D01*
Y214186D01*
X119095D01*
Y214049D01*
X118958D01*
Y213911D01*
X118820D01*
Y211714D01*
X118958D01*
Y211852D01*
X119232D01*
Y211989D01*
X119370D01*
Y212126D01*
X119507D01*
Y212263D01*
X119644D01*
Y212401D01*
X119782D01*
Y212538D01*
X119919D01*
Y212675D01*
X120056D01*
Y212813D01*
X120331D01*
Y212950D01*
X120468D01*
Y213087D01*
X120605D01*
Y213225D01*
X120743D01*
Y213362D01*
X120880D01*
Y213499D01*
X121017D01*
Y213637D01*
X121155D01*
Y213774D01*
X121292D01*
Y213911D01*
X121429D01*
Y214049D01*
X121567D01*
Y214186D01*
X121704D01*
Y214323D01*
X121841D01*
Y214461D01*
X121979D01*
Y214598D01*
X122116D01*
Y214735D01*
X122253D01*
Y214872D01*
X122391D01*
Y215010D01*
X122528D01*
Y215147D01*
X122665D01*
Y215284D01*
X122802D01*
Y215422D01*
X122940D01*
Y215559D01*
X123077D01*
Y215696D01*
X123215D01*
Y215834D01*
X123352D01*
Y215971D01*
X123489D01*
Y216108D01*
X123626D01*
Y216246D01*
X123764D01*
Y216383D01*
X123901D01*
Y216520D01*
X124038D01*
Y216658D01*
X124176D01*
Y216932D01*
X124313D01*
Y217069D01*
X124450D01*
Y217207D01*
X124588D01*
Y217344D01*
X124725D01*
Y217481D01*
X124862D01*
Y217619D01*
X125000D01*
Y217756D01*
X125137D01*
Y218031D01*
X125274D01*
Y218168D01*
X125412D01*
Y218305D01*
X125549D01*
Y218443D01*
X125686D01*
Y218580D01*
X125823D01*
Y218855D01*
X125961D01*
Y218992D01*
X126098D01*
Y219129D01*
X126236D01*
Y219267D01*
X126373D01*
Y219541D01*
X126510D01*
Y219679D01*
X126647D01*
Y219816D01*
X126785D01*
Y219953D01*
X126922D01*
Y220228D01*
X127059D01*
Y220365D01*
X127197D01*
Y220502D01*
X127334D01*
Y220777D01*
X127471D01*
Y220914D01*
X127609D01*
Y221052D01*
X127746D01*
Y221326D01*
X127883D01*
Y221464D01*
X128021D01*
Y221738D01*
X128158D01*
Y221876D01*
X128295D01*
Y222150D01*
X128433D01*
Y222288D01*
X128570D01*
Y222425D01*
X128707D01*
Y222700D01*
X128844D01*
Y222837D01*
X128982D01*
Y223111D01*
X129119D01*
Y223249D01*
X129256D01*
Y223524D01*
X129394D01*
Y223798D01*
X129531D01*
Y223935D01*
X129668D01*
Y224210D01*
X129806D01*
Y224347D01*
X129943D01*
Y224622D01*
X130080D01*
Y224897D01*
X130218D01*
Y225034D01*
X130355D01*
Y225309D01*
X130492D01*
Y225583D01*
X130630D01*
Y225721D01*
X130767D01*
Y225995D01*
X130904D01*
Y226270D01*
X131042D01*
Y226544D01*
X131179D01*
Y226682D01*
X131316D01*
Y226956D01*
X131454D01*
Y227231D01*
X131591D01*
Y227506D01*
X131728D01*
Y227780D01*
X131866D01*
Y228055D01*
X132003D01*
Y228330D01*
X132140D01*
Y228604D01*
X132277D01*
Y228879D01*
X132415D01*
Y229153D01*
X132552D01*
Y229428D01*
X132689D01*
Y229703D01*
X132827D01*
Y229977D01*
X132964D01*
Y230252D01*
X133101D01*
Y230527D01*
X133239D01*
Y230939D01*
X133376D01*
Y231213D01*
X133513D01*
Y231488D01*
X133651D01*
Y231900D01*
X133788D01*
Y232174D01*
X133925D01*
Y232586D01*
X134063D01*
Y232861D01*
X134200D01*
Y233273D01*
X134337D01*
Y233548D01*
X134474D01*
Y233960D01*
X134612D01*
Y234371D01*
X134749D01*
Y234783D01*
X134887D01*
Y235195D01*
X135024D01*
Y235607D01*
X135161D01*
Y236019D01*
X135298D01*
Y236431D01*
X135436D01*
Y236843D01*
X135573D01*
Y237255D01*
X135710D01*
Y237805D01*
X135848D01*
Y238216D01*
X135985D01*
Y238766D01*
X136122D01*
Y239315D01*
X136260D01*
Y239864D01*
X136397D01*
Y240551D01*
X136534D01*
Y241100D01*
X136672D01*
Y241649D01*
X136809D01*
Y242473D01*
X136946D01*
Y243160D01*
X137084D01*
Y243984D01*
X137221D01*
Y244945D01*
X137358D01*
Y246043D01*
X137495D01*
Y247279D01*
X137633D01*
Y249065D01*
X137770D01*
Y255656D01*
X137633D01*
Y257304D01*
X137495D01*
Y258677D01*
X137358D01*
Y259638D01*
X137221D01*
Y260599D01*
X137084D01*
Y261423D01*
X136946D01*
Y262247D01*
X136809D01*
Y262934D01*
X136672D01*
Y263483D01*
X136534D01*
Y264169D01*
X136397D01*
Y264719D01*
X136260D01*
Y265268D01*
X136122D01*
Y265817D01*
X135985D01*
Y266367D01*
X135848D01*
Y266779D01*
X135710D01*
Y267328D01*
X135573D01*
Y267740D01*
X135436D01*
Y268152D01*
X135298D01*
Y268701D01*
X135161D01*
Y269113D01*
X135024D01*
Y269525D01*
X134887D01*
Y269799D01*
X134749D01*
Y270211D01*
X134612D01*
Y270623D01*
X134474D01*
Y271035D01*
X134337D01*
Y271310D01*
X134200D01*
Y271722D01*
X134063D01*
Y271996D01*
X133925D01*
Y272409D01*
X133788D01*
Y272683D01*
X133651D01*
Y273095D01*
X133513D01*
Y273370D01*
X133376D01*
Y273644D01*
X133239D01*
Y274056D01*
X133101D01*
Y274331D01*
X132964D01*
Y274606D01*
X132827D01*
Y274880D01*
X132689D01*
Y275155D01*
X132552D01*
Y275429D01*
X132415D01*
Y275704D01*
X132277D01*
Y275979D01*
X132140D01*
Y276253D01*
X132003D01*
Y276528D01*
X131866D01*
Y276803D01*
X131728D01*
Y277077D01*
X131591D01*
Y277352D01*
X131454D01*
Y277626D01*
X131316D01*
Y277901D01*
X131179D01*
Y278176D01*
X131042D01*
Y278313D01*
X130904D01*
Y278588D01*
X130767D01*
Y278862D01*
X130630D01*
Y279137D01*
X130492D01*
Y279274D01*
X130355D01*
Y279549D01*
X130218D01*
Y279824D01*
X130080D01*
Y279961D01*
X129943D01*
Y280236D01*
X129806D01*
Y280373D01*
X129668D01*
Y280648D01*
X129531D01*
Y280922D01*
X129394D01*
Y281059D01*
X129256D01*
Y281334D01*
X129119D01*
Y281471D01*
X128982D01*
Y281746D01*
X128844D01*
Y281883D01*
X128707D01*
Y282158D01*
X128570D01*
Y282295D01*
X128433D01*
Y282570D01*
X128295D01*
Y282707D01*
X128158D01*
Y282845D01*
X128021D01*
Y283119D01*
X127883D01*
Y283257D01*
X127746D01*
Y283531D01*
X127609D01*
Y283668D01*
X127471D01*
Y283806D01*
X127334D01*
Y284081D01*
X127197D01*
Y284218D01*
X127059D01*
Y284355D01*
X126922D01*
Y284630D01*
X126785D01*
Y284767D01*
X126647D01*
Y284904D01*
X126510D01*
Y285179D01*
X126373D01*
Y285316D01*
X126236D01*
Y285454D01*
X126098D01*
Y285591D01*
X125961D01*
Y285866D01*
X125823D01*
Y286003D01*
X125686D01*
Y286140D01*
X125549D01*
Y286278D01*
X125412D01*
Y286415D01*
X125274D01*
Y286689D01*
X125137D01*
Y286827D01*
X125000D01*
Y286964D01*
X124862D01*
Y287101D01*
X124725D01*
Y287239D01*
X124588D01*
Y287376D01*
X124450D01*
Y287513D01*
X124313D01*
Y287788D01*
X124176D01*
Y287925D01*
X124038D01*
Y288063D01*
X123901D01*
Y288200D01*
X123764D01*
Y288337D01*
X123626D01*
Y288475D01*
X123489D01*
Y288612D01*
X123352D01*
Y288749D01*
X123215D01*
Y288887D01*
X123077D01*
Y289024D01*
X122940D01*
Y289161D01*
X122802D01*
Y289298D01*
X122665D01*
Y289436D01*
X122528D01*
Y289573D01*
X122391D01*
Y289711D01*
X122253D01*
Y289848D01*
X122116D01*
Y289985D01*
X121979D01*
Y290122D01*
X121841D01*
Y290260D01*
X121704D01*
Y290397D01*
X121567D01*
Y290534D01*
X121429D01*
Y290672D01*
X121292D01*
Y290809D01*
X121155D01*
Y290946D01*
X121017D01*
Y291084D01*
X120880D01*
Y291221D01*
X120743D01*
Y291358D01*
X120605D01*
Y291496D01*
X120468D01*
Y291633D01*
X120331D01*
Y291770D01*
X120194D01*
Y291908D01*
X119919D01*
Y292045D01*
X119782D01*
Y292182D01*
X119644D01*
Y292320D01*
X119507D01*
Y292457D01*
X119370D01*
Y292594D01*
X119232D01*
Y292731D01*
X119095D01*
Y292869D01*
X118820D01*
Y293006D01*
X118683D01*
Y293143D01*
X118546D01*
Y293281D01*
X118408D01*
Y293418D01*
X118134D01*
Y293555D01*
X117996D01*
Y293693D01*
X117859D01*
Y293830D01*
X117722D01*
Y293967D01*
X117447D01*
Y294105D01*
X117310D01*
Y294242D01*
X117172D01*
Y294379D01*
X117035D01*
Y294517D01*
X116761D01*
Y294654D01*
X116623D01*
Y294791D01*
X116486D01*
Y294928D01*
X116211D01*
Y295066D01*
X116074D01*
Y295203D01*
X115937D01*
Y295340D01*
X115662D01*
Y295478D01*
X115525D01*
Y295615D01*
X115250D01*
Y295753D01*
X115113D01*
Y295890D01*
X114975D01*
Y296027D01*
X114701D01*
Y296164D01*
X114564D01*
Y296302D01*
X114289D01*
Y296439D01*
X114151D01*
Y296576D01*
X113877D01*
Y296714D01*
X113740D01*
Y296851D01*
X113465D01*
Y296988D01*
X113328D01*
Y297126D01*
X113053D01*
Y297263D01*
X112778D01*
Y297400D01*
X112641D01*
Y297538D01*
X112366D01*
Y297675D01*
X112229D01*
Y297812D01*
X111954D01*
Y297950D01*
X111680D01*
Y298087D01*
X111405D01*
Y298224D01*
X111268D01*
Y298361D01*
X110993D01*
Y298499D01*
X110719D01*
Y298636D01*
X110444D01*
Y298773D01*
X110169D01*
Y298911D01*
X110032D01*
Y299048D01*
X109757D01*
Y299185D01*
X109483D01*
Y299323D01*
X109208D01*
Y299460D01*
X108933D01*
Y299597D01*
X108659D01*
Y299735D01*
X108384D01*
Y299872D01*
X108110D01*
Y300009D01*
X107835D01*
Y300147D01*
X107560D01*
Y300284D01*
X107286D01*
Y300421D01*
X107011D01*
Y300559D01*
X106736D01*
Y300696D01*
X106462D01*
Y300833D01*
X106050D01*
Y300970D01*
X105775D01*
Y301108D01*
X105500D01*
Y301245D01*
X105089D01*
Y301383D01*
X104814D01*
Y301520D01*
X104402D01*
Y301657D01*
X104127D01*
Y301794D01*
X103715D01*
Y301932D01*
X103441D01*
Y302069D01*
X103029D01*
Y302206D01*
X102617D01*
Y302344D01*
X102205D01*
Y302481D01*
X101793D01*
Y302618D01*
X101381D01*
Y302756D01*
X100969D01*
Y302893D01*
X100557D01*
Y303030D01*
X100145D01*
Y303168D01*
X99733D01*
Y303305D01*
X99184D01*
Y303442D01*
X98772D01*
Y303580D01*
X98223D01*
Y303717D01*
X97673D01*
Y303854D01*
X97124D01*
Y303992D01*
X96575D01*
Y304129D01*
X95888D01*
Y304266D01*
X95202D01*
Y304403D01*
X94515D01*
Y304541D01*
X93828D01*
Y304678D01*
X93005D01*
Y304815D01*
X92043D01*
Y304953D01*
X90945D01*
Y305090D01*
X89572D01*
Y305227D01*
X89434D01*
Y305090D01*
X89297D01*
Y305227D01*
X87787D01*
Y305365D01*
D02*
G37*
G36*
X51535Y293693D02*
X51397D01*
Y293555D01*
X51260D01*
Y293418D01*
X51123D01*
Y293281D01*
X50848D01*
Y293143D01*
X50711D01*
Y293006D01*
X50574D01*
Y292869D01*
X50436D01*
Y292731D01*
X50299D01*
Y292594D01*
X50024D01*
Y292457D01*
X49887D01*
Y292320D01*
X49750D01*
Y292182D01*
X49612D01*
Y292045D01*
X49475D01*
Y291908D01*
X49338D01*
Y291770D01*
X49200D01*
Y291633D01*
X49063D01*
Y291496D01*
X48788D01*
Y291358D01*
X48651D01*
Y291221D01*
X48514D01*
Y291084D01*
X48376D01*
Y290946D01*
X48239D01*
Y290809D01*
X48102D01*
Y290672D01*
X47965D01*
Y290534D01*
X47827D01*
Y290397D01*
X47690D01*
Y290260D01*
X47552D01*
Y290122D01*
X47415D01*
Y289985D01*
X47278D01*
Y289848D01*
X47141D01*
Y289711D01*
X47003D01*
Y289573D01*
X46866D01*
Y289436D01*
X46729D01*
Y289298D01*
X46591D01*
Y289161D01*
X46454D01*
Y289024D01*
X46317D01*
Y288887D01*
X46179D01*
Y288749D01*
X46042D01*
Y288612D01*
X45905D01*
Y288475D01*
X45767D01*
Y288337D01*
X45630D01*
Y288200D01*
X45493D01*
Y287925D01*
X45356D01*
Y287788D01*
X45218D01*
Y287651D01*
X45081D01*
Y287513D01*
X44943D01*
Y287376D01*
X44806D01*
Y287239D01*
X44669D01*
Y287101D01*
X44532D01*
Y286964D01*
X44394D01*
Y286689D01*
X44257D01*
Y286552D01*
X44120D01*
Y286415D01*
X43982D01*
Y286278D01*
X43845D01*
Y286140D01*
X43708D01*
Y285866D01*
X43570D01*
Y285728D01*
X43433D01*
Y285591D01*
X43296D01*
Y285454D01*
X43158D01*
Y285179D01*
X43021D01*
Y285042D01*
X42884D01*
Y284904D01*
X42746D01*
Y284767D01*
X42609D01*
Y284492D01*
X42472D01*
Y284355D01*
X42334D01*
Y284218D01*
X42197D01*
Y283943D01*
X42060D01*
Y283806D01*
X41922D01*
Y283668D01*
X41785D01*
Y283394D01*
X41648D01*
Y283257D01*
X41511D01*
Y282982D01*
X41373D01*
Y282845D01*
X41236D01*
Y282707D01*
X41099D01*
Y282433D01*
X40961D01*
Y282295D01*
X40824D01*
Y282021D01*
X40687D01*
Y281883D01*
X40549D01*
Y281609D01*
X40412D01*
Y281471D01*
X40275D01*
Y281197D01*
X40137D01*
Y281059D01*
X40000D01*
Y280785D01*
X39863D01*
Y280648D01*
X39725D01*
Y280373D01*
X39588D01*
Y280098D01*
X39451D01*
Y279961D01*
X39313D01*
Y279686D01*
X39176D01*
Y279412D01*
X39039D01*
Y279274D01*
X38902D01*
Y279000D01*
X38764D01*
Y278725D01*
X38627D01*
Y278588D01*
X38490D01*
Y278313D01*
X38352D01*
Y278039D01*
X38215D01*
Y277764D01*
X38078D01*
Y277489D01*
X37940D01*
Y277352D01*
X37803D01*
Y277077D01*
X37666D01*
Y276803D01*
X37528D01*
Y276528D01*
X37391D01*
Y276253D01*
X37254D01*
Y275979D01*
X37116D01*
Y275704D01*
X36979D01*
Y275429D01*
X36842D01*
Y275155D01*
X36704D01*
Y274880D01*
X36567D01*
Y274468D01*
X36430D01*
Y274194D01*
X36293D01*
Y273919D01*
X36155D01*
Y273644D01*
X36018D01*
Y273232D01*
X35880D01*
Y272958D01*
X35743D01*
Y272683D01*
X35606D01*
Y272271D01*
X35469D01*
Y271996D01*
X35331D01*
Y271585D01*
X35194D01*
Y271310D01*
X35057D01*
Y270898D01*
X34919D01*
Y270486D01*
X34782D01*
Y270074D01*
X34645D01*
Y269799D01*
X34507D01*
Y269387D01*
X34370D01*
Y268976D01*
X34233D01*
Y268564D01*
X34095D01*
Y268014D01*
X33958D01*
Y267602D01*
X33821D01*
Y267190D01*
X33684D01*
Y266641D01*
X33546D01*
Y266229D01*
X33409D01*
Y265680D01*
X33272D01*
Y265131D01*
X33134D01*
Y264581D01*
X32997D01*
Y264032D01*
X32860D01*
Y263346D01*
X32722D01*
Y262659D01*
X32585D01*
Y261972D01*
X32448D01*
Y261148D01*
X32310D01*
Y260187D01*
X32173D01*
Y259363D01*
X32036D01*
Y258265D01*
X31898D01*
Y256892D01*
X31761D01*
Y254832D01*
X31624D01*
Y249751D01*
X31761D01*
Y247691D01*
X31898D01*
Y246455D01*
X32036D01*
Y245357D01*
X32173D01*
Y244258D01*
X32310D01*
Y243435D01*
X32448D01*
Y242611D01*
X32585D01*
Y241924D01*
X32722D01*
Y241237D01*
X32860D01*
Y240551D01*
X32997D01*
Y240002D01*
X33134D01*
Y239452D01*
X33272D01*
Y238903D01*
X33409D01*
Y238354D01*
X33546D01*
Y237942D01*
X33684D01*
Y237393D01*
X33821D01*
Y236981D01*
X33958D01*
Y236569D01*
X34095D01*
Y236019D01*
X34233D01*
Y235607D01*
X34370D01*
Y235195D01*
X34507D01*
Y234921D01*
X34645D01*
Y234509D01*
X34782D01*
Y234097D01*
X34919D01*
Y233685D01*
X35057D01*
Y233410D01*
X35194D01*
Y232998D01*
X35331D01*
Y232586D01*
X35469D01*
Y232312D01*
X35606D01*
Y231900D01*
X35743D01*
Y231625D01*
X35880D01*
Y231350D01*
X36018D01*
Y230939D01*
X36155D01*
Y230664D01*
X36293D01*
Y230389D01*
X36430D01*
Y230115D01*
X36567D01*
Y229840D01*
X36704D01*
Y229428D01*
X36842D01*
Y229153D01*
X36979D01*
Y229016D01*
X37116D01*
Y228741D01*
X37254D01*
Y228330D01*
X37391D01*
Y228055D01*
X37528D01*
Y227918D01*
X37666D01*
Y227506D01*
X37803D01*
Y227368D01*
X37940D01*
Y227094D01*
X38078D01*
Y226819D01*
X38215D01*
Y226544D01*
X38352D01*
Y226270D01*
X38490D01*
Y226133D01*
X38627D01*
Y225858D01*
X38764D01*
Y225583D01*
X38902D01*
Y225309D01*
X39039D01*
Y225171D01*
X39176D01*
Y224897D01*
X39313D01*
Y224622D01*
X39451D01*
Y224485D01*
X39588D01*
Y224210D01*
X39725D01*
Y224073D01*
X39863D01*
Y223798D01*
X40000D01*
Y223524D01*
X40137D01*
Y223386D01*
X40275D01*
Y223111D01*
X40412D01*
Y222974D01*
X40549D01*
Y222700D01*
X40687D01*
Y222562D01*
X40824D01*
Y222288D01*
X40961D01*
Y222150D01*
X41099D01*
Y221876D01*
X41236D01*
Y221738D01*
X41373D01*
Y221601D01*
X41511D01*
Y221326D01*
X41648D01*
Y221189D01*
X41785D01*
Y221052D01*
X41922D01*
Y220777D01*
X42060D01*
Y220640D01*
X42197D01*
Y220365D01*
X42334D01*
Y220228D01*
X42472D01*
Y220091D01*
X42609D01*
Y219953D01*
X42746D01*
Y219679D01*
X42884D01*
Y219541D01*
X43021D01*
Y219404D01*
X43158D01*
Y219129D01*
X43296D01*
Y218992D01*
X43433D01*
Y218855D01*
X43570D01*
Y218717D01*
X43708D01*
Y218580D01*
X43845D01*
Y218305D01*
X43982D01*
Y218168D01*
X44120D01*
Y218031D01*
X44257D01*
Y217893D01*
X44394D01*
Y217756D01*
X44532D01*
Y217481D01*
X44669D01*
Y217344D01*
X44806D01*
Y217207D01*
X44943D01*
Y217069D01*
X45081D01*
Y216932D01*
X45218D01*
Y216795D01*
X45356D01*
Y216658D01*
X45493D01*
Y216520D01*
X45630D01*
Y216383D01*
X45767D01*
Y216108D01*
X45905D01*
Y215971D01*
X46042D01*
Y215834D01*
X46179D01*
Y215696D01*
X46317D01*
Y215559D01*
X46454D01*
Y215422D01*
X46591D01*
Y215284D01*
X46729D01*
Y215147D01*
X46866D01*
Y215010D01*
X47003D01*
Y214872D01*
X47141D01*
Y214735D01*
X47278D01*
Y214598D01*
X47415D01*
Y214461D01*
X47552D01*
Y214323D01*
X47690D01*
Y214186D01*
X47827D01*
Y214049D01*
X47965D01*
Y213911D01*
X48102D01*
Y213774D01*
X48239D01*
Y213637D01*
X48376D01*
Y213499D01*
X48514D01*
Y213362D01*
X48651D01*
Y213225D01*
X48926D01*
Y213087D01*
X49063D01*
Y212950D01*
X49200D01*
Y212813D01*
X49338D01*
Y212675D01*
X49475D01*
Y212538D01*
X49612D01*
Y212401D01*
X49750D01*
Y212263D01*
X49887D01*
Y212126D01*
X50162D01*
Y211989D01*
X50299D01*
Y211852D01*
X50436D01*
Y211714D01*
X50574D01*
Y211577D01*
X50711D01*
Y211439D01*
X50985D01*
Y211302D01*
X51123D01*
Y211165D01*
X51260D01*
Y211028D01*
X51397D01*
Y210890D01*
X51535D01*
Y210753D01*
X51809D01*
Y210616D01*
X51947D01*
Y210478D01*
X52084D01*
Y210341D01*
X52359D01*
Y210204D01*
X52496D01*
Y210066D01*
X52633D01*
Y209929D01*
X52771D01*
Y209792D01*
X53045D01*
Y209654D01*
X53183D01*
Y209517D01*
X53320D01*
Y209380D01*
X53594D01*
Y209242D01*
X53732D01*
Y209105D01*
X54007D01*
Y208968D01*
X54144D01*
Y208831D01*
X54281D01*
Y208693D01*
X54556D01*
Y208556D01*
X54693D01*
Y208419D01*
X54968D01*
Y208281D01*
X55105D01*
Y208144D01*
X55380D01*
Y208007D01*
X55517D01*
Y207869D01*
X55792D01*
Y207732D01*
X55929D01*
Y207595D01*
X56203D01*
Y207457D01*
X56341D01*
Y207320D01*
X56616D01*
Y207183D01*
X56890D01*
Y207045D01*
X57027D01*
Y206908D01*
X57302D01*
Y206771D01*
X57577D01*
Y206633D01*
X57714D01*
Y206496D01*
X57989D01*
Y206359D01*
X58263D01*
Y206221D01*
X58401D01*
Y206084D01*
X58675D01*
Y205947D01*
X58950D01*
Y205809D01*
X59225D01*
Y205672D01*
X59499D01*
Y205535D01*
X59637D01*
Y205397D01*
X59911D01*
Y205260D01*
X60186D01*
Y205123D01*
X60460D01*
Y204986D01*
X60735D01*
Y204848D01*
X61010D01*
Y204711D01*
X61284D01*
Y204574D01*
X61559D01*
Y204436D01*
X61834D01*
Y204299D01*
X62108D01*
Y204162D01*
X62520D01*
Y204024D01*
X62795D01*
Y203887D01*
X63069D01*
Y203750D01*
X63344D01*
Y203612D01*
X63756D01*
Y203475D01*
X64031D01*
Y203338D01*
X64305D01*
Y203200D01*
X64717D01*
Y203063D01*
X64992D01*
Y202926D01*
X65404D01*
Y202789D01*
X65679D01*
Y202651D01*
X66090D01*
Y202514D01*
X66502D01*
Y202377D01*
X66777D01*
Y202239D01*
X67189D01*
Y202102D01*
X67601D01*
Y201965D01*
X68013D01*
Y201827D01*
X68425D01*
Y201690D01*
X68837D01*
Y201553D01*
X69386D01*
Y201415D01*
X69798D01*
Y201278D01*
X70347D01*
Y201141D01*
X70759D01*
Y201003D01*
X71308D01*
Y200866D01*
X71858D01*
Y200729D01*
X72407D01*
Y200591D01*
X72956D01*
Y200454D01*
X73643D01*
Y200317D01*
X74329D01*
Y200180D01*
X75016D01*
Y200042D01*
X75703D01*
Y199905D01*
X76526D01*
Y199767D01*
X77488D01*
Y199630D01*
X78586D01*
Y199493D01*
X79960D01*
Y199356D01*
X81882D01*
Y199218D01*
X82294D01*
Y199356D01*
X82431D01*
Y199218D01*
X84079D01*
Y200866D01*
X82569D01*
Y201003D01*
X80234D01*
Y201141D01*
X78998D01*
Y201278D01*
X77762D01*
Y201415D01*
X76801D01*
Y201553D01*
X75977D01*
Y201690D01*
X75291D01*
Y201827D01*
X74467D01*
Y201965D01*
X73917D01*
Y202102D01*
X73231D01*
Y202239D01*
X72682D01*
Y202377D01*
X72132D01*
Y202514D01*
X71583D01*
Y202651D01*
X71034D01*
Y202789D01*
X70622D01*
Y202926D01*
X70073D01*
Y203063D01*
X69661D01*
Y203200D01*
X69249D01*
Y203338D01*
X68699D01*
Y203475D01*
X68288D01*
Y203612D01*
X67875D01*
Y203750D01*
X67601D01*
Y203887D01*
X67189D01*
Y204024D01*
X66777D01*
Y204162D01*
X66365D01*
Y204299D01*
X66090D01*
Y204436D01*
X65679D01*
Y204574D01*
X65404D01*
Y204711D01*
X64992D01*
Y204848D01*
X64717D01*
Y204986D01*
X64443D01*
Y205123D01*
X64031D01*
Y205260D01*
X63756D01*
Y205397D01*
X63481D01*
Y205535D01*
X63207D01*
Y205672D01*
X62932D01*
Y205809D01*
X62657D01*
Y205947D01*
X62245D01*
Y206084D01*
X61971D01*
Y206221D01*
X61696D01*
Y206359D01*
X61422D01*
Y206496D01*
X61147D01*
Y206633D01*
X61010D01*
Y206771D01*
X60735D01*
Y206908D01*
X60460D01*
Y207045D01*
X60186D01*
Y207183D01*
X59911D01*
Y207320D01*
X59637D01*
Y207457D01*
X59499D01*
Y207595D01*
X59225D01*
Y207732D01*
X58950D01*
Y207869D01*
X58675D01*
Y208007D01*
X58538D01*
Y208144D01*
X58263D01*
Y208281D01*
X57989D01*
Y208419D01*
X57851D01*
Y208556D01*
X57577D01*
Y208693D01*
X57302D01*
Y208831D01*
X57165D01*
Y208968D01*
X56890D01*
Y209105D01*
X56753D01*
Y209242D01*
X56478D01*
Y209380D01*
X56341D01*
Y209517D01*
X56066D01*
Y209654D01*
X55929D01*
Y209792D01*
X55654D01*
Y209929D01*
X55517D01*
Y210066D01*
X55242D01*
Y210204D01*
X55105D01*
Y210341D01*
X54968D01*
Y210478D01*
X54693D01*
Y210616D01*
X54556D01*
Y210753D01*
X54281D01*
Y210890D01*
X54144D01*
Y211028D01*
X54007D01*
Y211165D01*
X53732D01*
Y211302D01*
X53594D01*
Y211439D01*
X53457D01*
Y211577D01*
X53183D01*
Y211714D01*
X53045D01*
Y211852D01*
X52908D01*
Y211989D01*
X52771D01*
Y212126D01*
X52496D01*
Y212263D01*
X52359D01*
Y212401D01*
X52221D01*
Y212538D01*
X52084D01*
Y212675D01*
X51809D01*
Y212813D01*
X51672D01*
Y212950D01*
X51535D01*
Y213087D01*
X51397D01*
Y213225D01*
X51260D01*
Y213362D01*
X51123D01*
Y213499D01*
X50848D01*
Y213637D01*
X50711D01*
Y213774D01*
X50574D01*
Y213911D01*
X50436D01*
Y214049D01*
X50299D01*
Y214186D01*
X50162D01*
Y214323D01*
X50024D01*
Y214461D01*
X49887D01*
Y214598D01*
X49750D01*
Y214735D01*
X49475D01*
Y214872D01*
X49338D01*
Y215010D01*
X49200D01*
Y215147D01*
X49063D01*
Y215284D01*
X48926D01*
Y215422D01*
X48788D01*
Y215559D01*
X48651D01*
Y215696D01*
X48514D01*
Y215834D01*
X48376D01*
Y215971D01*
X48239D01*
Y216108D01*
X48102D01*
Y216246D01*
X47965D01*
Y216383D01*
X47827D01*
Y216520D01*
X47690D01*
Y216658D01*
X47552D01*
Y216795D01*
X47415D01*
Y216932D01*
X47278D01*
Y217069D01*
X47141D01*
Y217344D01*
X47003D01*
Y217481D01*
X46866D01*
Y217619D01*
X46729D01*
Y217756D01*
X46591D01*
Y217893D01*
X46454D01*
Y218031D01*
X46317D01*
Y218168D01*
X46179D01*
Y218305D01*
X46042D01*
Y218443D01*
X45905D01*
Y218717D01*
X45767D01*
Y218855D01*
X45630D01*
Y218992D01*
X45493D01*
Y219129D01*
X45356D01*
Y219267D01*
X45218D01*
Y219404D01*
X45081D01*
Y219679D01*
X44943D01*
Y219816D01*
X44806D01*
Y219953D01*
X44669D01*
Y220091D01*
X44532D01*
Y220365D01*
X44394D01*
Y220502D01*
X44257D01*
Y220640D01*
X44120D01*
Y220777D01*
X43982D01*
Y221052D01*
X43845D01*
Y221189D01*
X43708D01*
Y221326D01*
X43570D01*
Y221601D01*
X43433D01*
Y221738D01*
X43296D01*
Y221876D01*
X43158D01*
Y222150D01*
X43021D01*
Y222288D01*
X42884D01*
Y222562D01*
X42746D01*
Y222700D01*
X42609D01*
Y222837D01*
X42472D01*
Y223111D01*
X42334D01*
Y223249D01*
X42197D01*
Y223524D01*
X42060D01*
Y223661D01*
X41922D01*
Y223935D01*
X41785D01*
Y224073D01*
X41648D01*
Y224347D01*
X41511D01*
Y224485D01*
X41373D01*
Y224759D01*
X41236D01*
Y224897D01*
X41099D01*
Y225171D01*
X40961D01*
Y225446D01*
X40824D01*
Y225583D01*
X40687D01*
Y225858D01*
X40549D01*
Y226133D01*
X40412D01*
Y226270D01*
X40275D01*
Y226544D01*
X40137D01*
Y226819D01*
X40000D01*
Y227094D01*
X39863D01*
Y227231D01*
X39725D01*
Y227506D01*
X39588D01*
Y227780D01*
X39451D01*
Y228055D01*
X39313D01*
Y228330D01*
X39176D01*
Y228604D01*
X39039D01*
Y228879D01*
X38902D01*
Y229153D01*
X38764D01*
Y229428D01*
X38627D01*
Y229565D01*
X38490D01*
Y229840D01*
X38352D01*
Y230252D01*
X38215D01*
Y230527D01*
X38078D01*
Y230801D01*
X37940D01*
Y231076D01*
X37803D01*
Y231350D01*
X37666D01*
Y231763D01*
X37528D01*
Y232037D01*
X37391D01*
Y232312D01*
X37254D01*
Y232724D01*
X37116D01*
Y232998D01*
X36979D01*
Y233410D01*
X36842D01*
Y233685D01*
X36704D01*
Y234097D01*
X36567D01*
Y234371D01*
X36430D01*
Y234783D01*
X36293D01*
Y235195D01*
X36155D01*
Y235607D01*
X36018D01*
Y236019D01*
X35880D01*
Y236431D01*
X35743D01*
Y236843D01*
X35606D01*
Y237255D01*
X35469D01*
Y237667D01*
X35331D01*
Y238216D01*
X35194D01*
Y238628D01*
X35057D01*
Y239178D01*
X34919D01*
Y239727D01*
X34782D01*
Y240276D01*
X34645D01*
Y240826D01*
X34507D01*
Y241512D01*
X34370D01*
Y242199D01*
X34233D01*
Y242885D01*
X34095D01*
Y243709D01*
X33958D01*
Y244533D01*
X33821D01*
Y245357D01*
X33684D01*
Y246593D01*
X33546D01*
Y248103D01*
X33409D01*
Y250300D01*
X33272D01*
Y250438D01*
X33409D01*
Y250575D01*
X33272D01*
Y254008D01*
X33409D01*
Y256480D01*
X33546D01*
Y257990D01*
X33684D01*
Y259089D01*
X33821D01*
Y260050D01*
X33958D01*
Y260874D01*
X34095D01*
Y261835D01*
X34233D01*
Y262384D01*
X34370D01*
Y263071D01*
X34507D01*
Y263757D01*
X34645D01*
Y264307D01*
X34782D01*
Y264856D01*
X34919D01*
Y265405D01*
X35057D01*
Y265955D01*
X35194D01*
Y266367D01*
X35331D01*
Y266916D01*
X35469D01*
Y267328D01*
X35606D01*
Y267740D01*
X35743D01*
Y268152D01*
X35880D01*
Y268701D01*
X36018D01*
Y268976D01*
X36155D01*
Y269387D01*
X36293D01*
Y269799D01*
X36430D01*
Y270211D01*
X36567D01*
Y270486D01*
X36704D01*
Y270898D01*
X36842D01*
Y271310D01*
X36979D01*
Y271585D01*
X37116D01*
Y271996D01*
X37254D01*
Y272271D01*
X37391D01*
Y272546D01*
X37528D01*
Y272958D01*
X37666D01*
Y273232D01*
X37803D01*
Y273507D01*
X37940D01*
Y273782D01*
X38078D01*
Y274056D01*
X38215D01*
Y274331D01*
X38352D01*
Y274743D01*
X38490D01*
Y275018D01*
X38627D01*
Y275292D01*
X38764D01*
Y275567D01*
X38902D01*
Y275841D01*
X39039D01*
Y275979D01*
X39176D01*
Y276253D01*
X39313D01*
Y276528D01*
X39451D01*
Y276803D01*
X39588D01*
Y277077D01*
X39725D01*
Y277352D01*
X39863D01*
Y277626D01*
X40000D01*
Y277764D01*
X40137D01*
Y278039D01*
X40275D01*
Y278313D01*
X40412D01*
Y278450D01*
X40549D01*
Y278725D01*
X40687D01*
Y279000D01*
X40824D01*
Y279137D01*
X40961D01*
Y279412D01*
X41099D01*
Y279686D01*
X41236D01*
Y279824D01*
X41373D01*
Y280098D01*
X41511D01*
Y280236D01*
X41648D01*
Y280510D01*
X41785D01*
Y280648D01*
X41922D01*
Y280922D01*
X42060D01*
Y281059D01*
X42197D01*
Y281334D01*
X42334D01*
Y281471D01*
X42472D01*
Y281746D01*
X42609D01*
Y281883D01*
X42746D01*
Y282158D01*
X42884D01*
Y282295D01*
X43021D01*
Y282433D01*
X43158D01*
Y282707D01*
X43296D01*
Y282845D01*
X43433D01*
Y282982D01*
X43570D01*
Y283257D01*
X43708D01*
Y283394D01*
X43845D01*
Y283531D01*
X43982D01*
Y283806D01*
X44120D01*
Y283943D01*
X44257D01*
Y284081D01*
X44394D01*
Y284218D01*
X44532D01*
Y284492D01*
X44669D01*
Y284630D01*
X44806D01*
Y284767D01*
X44943D01*
Y284904D01*
X45081D01*
Y285179D01*
X45218D01*
Y285316D01*
X45356D01*
Y285454D01*
X45493D01*
Y285591D01*
X45630D01*
Y285728D01*
X45767D01*
Y286003D01*
X45905D01*
Y286140D01*
X46042D01*
Y286278D01*
X46179D01*
Y286415D01*
X46317D01*
Y286552D01*
X46454D01*
Y286689D01*
X46591D01*
Y286827D01*
X46729D01*
Y286964D01*
X46866D01*
Y287101D01*
X47003D01*
Y287376D01*
X47141D01*
Y287513D01*
X47278D01*
Y287651D01*
X47415D01*
Y287788D01*
X47552D01*
Y287925D01*
X47690D01*
Y288063D01*
X47827D01*
Y288200D01*
X47965D01*
Y288337D01*
X48102D01*
Y288475D01*
X48239D01*
Y288612D01*
X48376D01*
Y288749D01*
X48514D01*
Y288887D01*
X48651D01*
Y289024D01*
X48788D01*
Y289161D01*
X48926D01*
Y289298D01*
X49063D01*
Y289436D01*
X49200D01*
Y289573D01*
X49338D01*
Y289711D01*
X49475D01*
Y289848D01*
X49612D01*
Y289985D01*
X49750D01*
Y290122D01*
X50024D01*
Y290260D01*
X50162D01*
Y290397D01*
X50299D01*
Y290534D01*
X50436D01*
Y290672D01*
X50574D01*
Y290809D01*
X50711D01*
Y290946D01*
X50848D01*
Y291084D01*
X50985D01*
Y291221D01*
X51260D01*
Y291358D01*
X51397D01*
Y291496D01*
X51535D01*
Y293693D01*
D02*
G37*
G36*
X115662Y207595D02*
X86688D01*
Y207457D01*
X86551D01*
Y207320D01*
X86413D01*
Y207183D01*
X86276D01*
Y206908D01*
X86139D01*
Y187958D01*
X86276D01*
Y187272D01*
X86413D01*
Y186860D01*
X86551D01*
Y186722D01*
X86688D01*
Y186585D01*
X86825D01*
Y186448D01*
X86963D01*
Y186310D01*
X87100D01*
Y186173D01*
X87237D01*
Y186036D01*
X87375D01*
Y185898D01*
X87512D01*
Y185761D01*
X87649D01*
Y185624D01*
X87787D01*
Y185487D01*
X87924D01*
Y185349D01*
X88061D01*
Y185212D01*
X88198D01*
Y185075D01*
X88336D01*
Y184937D01*
X88473D01*
Y184800D01*
X88610D01*
Y184663D01*
X88748D01*
Y184525D01*
X88885D01*
Y184388D01*
X89022D01*
Y184251D01*
X89160D01*
Y184113D01*
X89297D01*
Y183976D01*
X89434D01*
Y183839D01*
X89572D01*
Y183701D01*
X89709D01*
Y183564D01*
X89846D01*
Y183427D01*
X89984D01*
Y183289D01*
X90121D01*
Y183152D01*
X90258D01*
Y183015D01*
X90396D01*
Y182878D01*
X90533D01*
Y182740D01*
X90808D01*
Y182603D01*
X91357D01*
Y182465D01*
X110856D01*
Y182603D01*
X111405D01*
Y182740D01*
X111817D01*
Y182878D01*
X111954D01*
Y183015D01*
X112092D01*
Y183152D01*
X112229D01*
Y183289D01*
X112366D01*
Y183427D01*
X112504D01*
Y183564D01*
X112641D01*
Y183701D01*
X112778D01*
Y183839D01*
X112916D01*
Y183976D01*
X113053D01*
Y184113D01*
X113190D01*
Y184251D01*
X113328D01*
Y184388D01*
X113465D01*
Y184525D01*
X113602D01*
Y184663D01*
X113740D01*
Y184800D01*
X113877D01*
Y184937D01*
X114014D01*
Y185075D01*
X114151D01*
Y185212D01*
X114289D01*
Y185349D01*
X114426D01*
Y185487D01*
X114564D01*
Y185624D01*
X114701D01*
Y185761D01*
X114838D01*
Y185898D01*
X114975D01*
Y186036D01*
X115113D01*
Y186173D01*
X115250D01*
Y186310D01*
X115387D01*
Y186448D01*
X115525D01*
Y186585D01*
X115662D01*
Y186722D01*
X115799D01*
Y186997D01*
X115937D01*
Y187546D01*
X116074D01*
Y207183D01*
X115937D01*
Y207320D01*
X115799D01*
Y207457D01*
X115662D01*
Y207595D01*
D02*
G37*
%LPD*%
G36*
X100420Y219267D02*
X93142D01*
Y229565D01*
X100420D01*
Y219267D01*
D02*
G37*
G36*
X108796Y190018D02*
X93554D01*
Y190293D01*
X93417D01*
Y190430D01*
X93554D01*
Y190705D01*
X93417D01*
Y190842D01*
X93554D01*
Y199767D01*
X93417D01*
Y199905D01*
X93554D01*
Y200042D01*
X108796D01*
Y190018D01*
D02*
G37*
%LPC*%
G36*
X192783Y299195D02*
X189935Y298137D01*
X189583Y298011D01*
X189244Y297912D01*
X188934Y297813D01*
X188652Y297743D01*
X188413Y297686D01*
X188314Y297658D01*
X188215Y297644D01*
X188159Y297616D01*
X188103D01*
X188074Y297602D01*
X188060D01*
X188384Y297503D01*
X188723Y297390D01*
X189061Y297278D01*
X189385Y297165D01*
X189526Y297108D01*
X189667Y297066D01*
X189794Y297024D01*
X189893Y296982D01*
X189977Y296953D01*
X190048Y296925D01*
X190090Y296911D01*
X190104D01*
X192783Y295896D01*
Y299195D01*
D02*
G37*
G36*
X207012Y280121D02*
X206942D01*
X206928D01*
X206815Y280107D01*
X206702Y280093D01*
X206618Y280065D01*
X206533Y280037D01*
X206462Y280009D01*
X206406Y279995D01*
X206378Y279966D01*
X206364D01*
X206195Y279825D01*
X206082Y279656D01*
X206040Y279600D01*
X206011Y279543D01*
X205983Y279501D01*
Y279487D01*
X205927Y279346D01*
X205885Y279191D01*
X205842Y279022D01*
X205814Y278853D01*
X205786Y278698D01*
X205758Y278557D01*
X205744Y278472D01*
Y278444D01*
X205701Y278204D01*
X205673Y277979D01*
X205631Y277781D01*
X205588Y277584D01*
X205546Y277401D01*
X205504Y277246D01*
X205476Y277091D01*
X205433Y276964D01*
X205405Y276851D01*
X205377Y276752D01*
X205349Y276668D01*
X205321Y276597D01*
X205307Y276541D01*
X205292Y276499D01*
X205278Y276484D01*
Y276470D01*
X205730Y276484D01*
X206011Y276499D01*
X206251Y276513D01*
X206448Y276541D01*
X206618Y276583D01*
X206744Y276625D01*
X206843Y276654D01*
X206900Y276668D01*
X206914Y276682D01*
X207097Y276795D01*
X207266Y276907D01*
X207407Y277048D01*
X207520Y277175D01*
X207619Y277288D01*
X207689Y277387D01*
X207731Y277443D01*
X207745Y277471D01*
X207844Y277683D01*
X207915Y277894D01*
X207971Y278092D01*
X207999Y278289D01*
X208027Y278444D01*
X208041Y278585D01*
Y278698D01*
X208027Y278951D01*
X207999Y279163D01*
X207943Y279346D01*
X207886Y279501D01*
X207830Y279614D01*
X207773Y279699D01*
X207745Y279755D01*
X207731Y279769D01*
X207604Y279882D01*
X207463Y279966D01*
X207337Y280037D01*
X207210Y280079D01*
X207097Y280107D01*
X207012Y280121D01*
D02*
G37*
G36*
X194982Y275216D02*
X194911D01*
X194897D01*
X194785Y275202D01*
X194672Y275187D01*
X194587Y275159D01*
X194503Y275131D01*
X194432Y275103D01*
X194376Y275089D01*
X194348Y275061D01*
X194333D01*
X194164Y274920D01*
X194051Y274750D01*
X194009Y274694D01*
X193981Y274638D01*
X193953Y274595D01*
Y274581D01*
X193897Y274440D01*
X193854Y274285D01*
X193812Y274116D01*
X193784Y273947D01*
X193755Y273792D01*
X193727Y273651D01*
X193713Y273566D01*
Y273538D01*
X193671Y273298D01*
X193643Y273073D01*
X193600Y272876D01*
X193558Y272678D01*
X193516Y272495D01*
X193474Y272340D01*
X193445Y272185D01*
X193403Y272058D01*
X193375Y271945D01*
X193347Y271847D01*
X193319Y271762D01*
X193290Y271691D01*
X193276Y271635D01*
X193262Y271593D01*
X193248Y271579D01*
Y271565D01*
X193699Y271579D01*
X193981Y271593D01*
X194221Y271607D01*
X194418Y271635D01*
X194587Y271677D01*
X194714Y271720D01*
X194813Y271748D01*
X194869Y271762D01*
X194883Y271776D01*
X195067Y271889D01*
X195236Y272002D01*
X195377Y272143D01*
X195489Y272269D01*
X195588Y272382D01*
X195659Y272481D01*
X195701Y272537D01*
X195715Y272565D01*
X195814Y272777D01*
X195884Y272988D01*
X195940Y273186D01*
X195969Y273383D01*
X195997Y273538D01*
X196011Y273679D01*
Y273792D01*
X195997Y274046D01*
X195969Y274257D01*
X195912Y274440D01*
X195856Y274595D01*
X195800Y274708D01*
X195743Y274793D01*
X195715Y274849D01*
X195701Y274863D01*
X195574Y274976D01*
X195433Y275061D01*
X195306Y275131D01*
X195179Y275173D01*
X195067Y275202D01*
X194982Y275216D01*
D02*
G37*
G36*
X193403Y260146D02*
X193333D01*
X193290D01*
X193276D01*
X193022D01*
X192783Y260118D01*
X192557Y260090D01*
X192360Y260061D01*
X192177Y260019D01*
X192008Y259977D01*
X191852Y259935D01*
X191711Y259878D01*
X191599Y259822D01*
X191500Y259779D01*
X191415Y259737D01*
X191345Y259695D01*
X191289Y259653D01*
X191246Y259639D01*
X191232Y259610D01*
X191218D01*
X191105Y259512D01*
X190993Y259399D01*
X190837Y259173D01*
X190711Y258948D01*
X190640Y258736D01*
X190584Y258553D01*
X190570Y258398D01*
X190555Y258342D01*
Y258271D01*
X190570Y258116D01*
X190584Y257975D01*
X190668Y257707D01*
X190767Y257468D01*
X190894Y257270D01*
X191021Y257115D01*
X191133Y256988D01*
X191218Y256918D01*
X191232Y256890D01*
X191246D01*
X191387Y256791D01*
X191528Y256706D01*
X191866Y256565D01*
X192219Y256467D01*
X192557Y256396D01*
X192726Y256368D01*
X192882Y256354D01*
X193022Y256340D01*
X193135D01*
X193234Y256326D01*
X193304D01*
X193361D01*
X193375D01*
X193615D01*
X193840Y256354D01*
X194037Y256382D01*
X194235Y256410D01*
X194404Y256453D01*
X194573Y256509D01*
X194714Y256551D01*
X194841Y256608D01*
X194954Y256664D01*
X195067Y256706D01*
X195137Y256763D01*
X195208Y256805D01*
X195264Y256833D01*
X195306Y256861D01*
X195320Y256890D01*
X195334D01*
X195447Y256988D01*
X195546Y257101D01*
X195701Y257327D01*
X195814Y257552D01*
X195884Y257764D01*
X195940Y257947D01*
X195955Y258102D01*
X195969Y258158D01*
Y258229D01*
X195955Y258370D01*
X195940Y258511D01*
X195870Y258764D01*
X195757Y259004D01*
X195630Y259202D01*
X195518Y259357D01*
X195405Y259484D01*
X195334Y259554D01*
X195306Y259568D01*
Y259582D01*
X195165Y259681D01*
X195024Y259765D01*
X194700Y259906D01*
X194362Y260005D01*
X194037Y260075D01*
X193741Y260118D01*
X193615Y260132D01*
X193502D01*
X193403Y260146D01*
D02*
G37*
G36*
X193389Y252562D02*
X193319D01*
X193276D01*
X193262D01*
X193022Y252548D01*
X192783Y252534D01*
X192571Y252505D01*
X192374Y252463D01*
X192191Y252421D01*
X192022Y252379D01*
X191881Y252322D01*
X191740Y252266D01*
X191627Y252209D01*
X191514Y252153D01*
X191430Y252111D01*
X191359Y252068D01*
X191303Y252026D01*
X191260Y251998D01*
X191246Y251970D01*
X191232D01*
X191119Y251857D01*
X191007Y251730D01*
X190837Y251490D01*
X190725Y251237D01*
X190640Y250997D01*
X190584Y250786D01*
X190570Y250630D01*
X190555Y250560D01*
Y250476D01*
X190570Y250306D01*
X190584Y250151D01*
X190654Y249869D01*
X190767Y249616D01*
X190894Y249404D01*
X191021Y249235D01*
X191119Y249108D01*
X191204Y249023D01*
X191218Y248995D01*
X191232D01*
X191359Y248883D01*
X191514Y248798D01*
X191824Y248643D01*
X192162Y248530D01*
X192473Y248460D01*
X192769Y248417D01*
X192896Y248403D01*
X193008D01*
X193093Y248389D01*
X193163D01*
X193206D01*
X193220D01*
X193474D01*
X193713Y248417D01*
X193925Y248445D01*
X194136Y248488D01*
X194319Y248530D01*
X194489Y248587D01*
X194644Y248629D01*
X194785Y248685D01*
X194897Y248741D01*
X195010Y248798D01*
X195095Y248854D01*
X195165Y248897D01*
X195222Y248939D01*
X195264Y248967D01*
X195278Y248981D01*
X195292Y248995D01*
X195405Y249108D01*
X195518Y249235D01*
X195687Y249475D01*
X195800Y249728D01*
X195884Y249954D01*
X195926Y250165D01*
X195955Y250320D01*
X195969Y250391D01*
Y250476D01*
X195955Y250645D01*
X195940Y250800D01*
X195870Y251096D01*
X195757Y251350D01*
X195630Y251561D01*
X195518Y251730D01*
X195405Y251857D01*
X195334Y251942D01*
X195306Y251956D01*
Y251970D01*
X195165Y252068D01*
X195024Y252167D01*
X194700Y252308D01*
X194362Y252421D01*
X194023Y252491D01*
X193727Y252534D01*
X193600Y252548D01*
X193488D01*
X193389Y252562D01*
D02*
G37*
G36*
X191683Y240509D02*
X188201D01*
Y237718D01*
X188215Y237464D01*
X188230Y237253D01*
X188244Y237083D01*
X188272Y236971D01*
X188286Y236886D01*
X188300Y236830D01*
Y236815D01*
X188370Y236632D01*
X188455Y236477D01*
X188540Y236336D01*
X188638Y236209D01*
X188737Y236125D01*
X188807Y236054D01*
X188864Y236012D01*
X188878Y235998D01*
X189047Y235899D01*
X189216Y235815D01*
X189400Y235758D01*
X189555Y235730D01*
X189696Y235702D01*
X189822Y235688D01*
X189893D01*
X189907D01*
X189921D01*
X190217Y235716D01*
X190471Y235772D01*
X190696Y235857D01*
X190880Y235956D01*
X191021Y236054D01*
X191133Y236139D01*
X191190Y236195D01*
X191218Y236223D01*
X191303Y236322D01*
X191373Y236449D01*
X191486Y236717D01*
X191570Y237013D01*
X191627Y237309D01*
X191655Y237577D01*
X191669Y237689D01*
Y237788D01*
X191683Y237887D01*
Y240509D01*
D02*
G37*
G36*
X207012Y233869D02*
X206942D01*
X206928D01*
X206815Y233855D01*
X206702Y233841D01*
X206618Y233813D01*
X206533Y233785D01*
X206462Y233756D01*
X206406Y233742D01*
X206378Y233714D01*
X206364D01*
X206195Y233573D01*
X206082Y233404D01*
X206040Y233348D01*
X206011Y233291D01*
X205983Y233249D01*
Y233235D01*
X205927Y233094D01*
X205885Y232939D01*
X205842Y232770D01*
X205814Y232600D01*
X205786Y232445D01*
X205758Y232304D01*
X205744Y232220D01*
Y232192D01*
X205701Y231952D01*
X205673Y231726D01*
X205631Y231529D01*
X205588Y231332D01*
X205546Y231148D01*
X205504Y230993D01*
X205476Y230838D01*
X205433Y230711D01*
X205405Y230599D01*
X205377Y230500D01*
X205349Y230415D01*
X205321Y230345D01*
X205307Y230289D01*
X205292Y230246D01*
X205278Y230232D01*
Y230218D01*
X205730Y230232D01*
X206011Y230246D01*
X206251Y230260D01*
X206448Y230289D01*
X206618Y230331D01*
X206744Y230373D01*
X206843Y230401D01*
X206900Y230415D01*
X206914Y230429D01*
X207097Y230542D01*
X207266Y230655D01*
X207407Y230796D01*
X207520Y230923D01*
X207619Y231036D01*
X207689Y231134D01*
X207731Y231191D01*
X207745Y231219D01*
X207844Y231430D01*
X207915Y231642D01*
X207971Y231839D01*
X207999Y232037D01*
X208027Y232192D01*
X208041Y232333D01*
Y232445D01*
X208027Y232699D01*
X207999Y232911D01*
X207943Y233094D01*
X207886Y233249D01*
X207830Y233362D01*
X207773Y233446D01*
X207745Y233503D01*
X207731Y233517D01*
X207604Y233630D01*
X207463Y233714D01*
X207337Y233785D01*
X207210Y233827D01*
X207097Y233855D01*
X207012Y233869D01*
D02*
G37*
G36*
X194982Y221379D02*
X194911D01*
X194897D01*
X194785Y221365D01*
X194672Y221351D01*
X194587Y221323D01*
X194503Y221295D01*
X194432Y221266D01*
X194376Y221252D01*
X194348Y221224D01*
X194333D01*
X194164Y221083D01*
X194051Y220914D01*
X194009Y220858D01*
X193981Y220801D01*
X193953Y220759D01*
Y220745D01*
X193897Y220604D01*
X193854Y220449D01*
X193812Y220280D01*
X193784Y220110D01*
X193755Y219956D01*
X193727Y219814D01*
X193713Y219730D01*
Y219702D01*
X193671Y219462D01*
X193643Y219237D01*
X193600Y219039D01*
X193558Y218842D01*
X193516Y218659D01*
X193474Y218503D01*
X193445Y218348D01*
X193403Y218221D01*
X193375Y218109D01*
X193347Y218010D01*
X193319Y217925D01*
X193290Y217855D01*
X193276Y217799D01*
X193262Y217756D01*
X193248Y217742D01*
Y217728D01*
X193699Y217742D01*
X193981Y217756D01*
X194221Y217770D01*
X194418Y217799D01*
X194587Y217841D01*
X194714Y217883D01*
X194813Y217911D01*
X194869Y217925D01*
X194883Y217940D01*
X195067Y218052D01*
X195236Y218165D01*
X195377Y218306D01*
X195489Y218433D01*
X195588Y218546D01*
X195659Y218644D01*
X195701Y218701D01*
X195715Y218729D01*
X195814Y218941D01*
X195884Y219152D01*
X195940Y219349D01*
X195969Y219547D01*
X195997Y219702D01*
X196011Y219843D01*
Y219956D01*
X195997Y220209D01*
X195969Y220421D01*
X195912Y220604D01*
X195856Y220759D01*
X195800Y220872D01*
X195743Y220956D01*
X195715Y221013D01*
X195701Y221027D01*
X195574Y221140D01*
X195433Y221224D01*
X195306Y221295D01*
X195179Y221337D01*
X195067Y221365D01*
X194982Y221379D01*
D02*
G37*
G36*
X204616Y214909D02*
X204292Y214866D01*
X203996Y214782D01*
X203742Y214683D01*
X203544Y214570D01*
X203375Y214472D01*
X203248Y214373D01*
X203178Y214317D01*
X203150Y214289D01*
X202966Y214063D01*
X202826Y213837D01*
X202727Y213598D01*
X202656Y213372D01*
X202614Y213189D01*
X202600Y213034D01*
X202586Y212978D01*
Y212893D01*
X202600Y212724D01*
X202614Y212569D01*
X202699Y212273D01*
X202811Y212019D01*
X202938Y211807D01*
X203065Y211638D01*
X203178Y211511D01*
X203263Y211441D01*
X203277Y211413D01*
X203291D01*
X203474Y211286D01*
X203685Y211173D01*
X203897Y211103D01*
X204122Y211032D01*
X204306Y210990D01*
X204475Y210962D01*
X204531D01*
X204573Y210947D01*
X204602D01*
X204616D01*
Y214909D01*
D02*
G37*
G36*
X192585Y210750D02*
X192261Y210708D01*
X191965Y210623D01*
X191711Y210525D01*
X191514Y210412D01*
X191345Y210313D01*
X191218Y210214D01*
X191147Y210158D01*
X191119Y210130D01*
X190936Y209904D01*
X190795Y209679D01*
X190696Y209439D01*
X190626Y209214D01*
X190584Y209030D01*
X190570Y208875D01*
X190555Y208819D01*
Y208734D01*
X190570Y208565D01*
X190584Y208410D01*
X190668Y208114D01*
X190781Y207860D01*
X190908Y207649D01*
X191035Y207480D01*
X191147Y207353D01*
X191232Y207282D01*
X191246Y207254D01*
X191260D01*
X191444Y207127D01*
X191655Y207014D01*
X191866Y206944D01*
X192092Y206873D01*
X192275Y206831D01*
X192444Y206803D01*
X192501D01*
X192543Y206789D01*
X192571D01*
X192585D01*
Y210750D01*
D02*
G37*
%LPD*%
D64*
X200328Y33332D02*
Y30000D01*
X203661Y33332D01*
X204494D01*
X205327Y32499D01*
Y30833D01*
X204494Y30000D01*
X151000Y30332D02*
Y27000D01*
X154332Y30332D01*
X155165D01*
X155998Y29499D01*
Y27833D01*
X155165Y27000D01*
Y31998D02*
X155998Y32831D01*
Y34497D01*
X155165Y35331D01*
X151833D01*
X151000Y34497D01*
Y32831D01*
X151833Y31998D01*
X155165D01*
X177309Y28000D02*
Y29666D01*
Y28833D01*
X182307D01*
X181474Y28000D01*
Y32165D02*
X182307Y32998D01*
Y34664D01*
X181474Y35498D01*
X178142D01*
X177309Y34664D01*
Y32998D01*
X178142Y32165D01*
X181474D01*
X21998Y29000D02*
Y32332D01*
X21165D01*
X17833Y29000D01*
X17000D01*
Y36497D02*
X21998D01*
X19499Y33998D01*
Y37331D01*
M02*
